FILE_TYPE = MACRO_DRAWING;
SET COLOR_WIRE YELLOW;
SET COLOR_PROP ORANGE;
SET COLOR_DOT WHITE;
SET COLOR_ARC YELLOW;
SET COLOR_BODY GREEN;
SET COLOR_NOTE PURPLE;
SET PROP_DISPLAY VALUE;
SET PAGE_NUMBER P14;
SET PATH_NUMBER P239;
FORCEADD OFFPAGE..2
R 2
(-3625 3275);
FORCEPROP 2 LAST $XR0 14 
J 0
(-3849 3275);
DISPLAY 0.638298 (-3849 3275);
PAINT MONO (-3849 3275);
FORCEPROP 2 LAST $XR1 10 
J 0
(-3939 3275);
DISPLAY 0.638298 (-3939 3275);
PAINT MONO (-3939 3275);
FORCEPROP 2 LAST CDS_LIB standard
J 0
(-3625 3275);
DISPLAY INVISIBLE (-3625 3275);
FORCEPROP 1 LAST OFFPAGE TRUE
J 2
(-3950 3150);
DISPLAY 0.872340 (-3950 3150);
PAINT GREEN (-3950 3150);
DISPLAY INVISIBLE (-3950 3150);
FORCEPROP 1 LAST COMMENT_BODY TRUE
J 2
(-3580 3180);
DISPLAY 0.872340 (-3580 3180);
PAINT PEACH (-3580 3180);
DISPLAY INVISIBLE (-3580 3180);
FORCEPROP 2 LAST PATH I1
J 0
(-3825 3325);
DISPLAY 1.021277 (-3825 3325);
DISPLAY INVISIBLE (-3825 3325);
FORCEADD AST2600A3GP..3
(525 3950);
FORCEPROP 1 LAST MATERIAL IC
J 0
(-483 4823);
DISPLAY 0.723404 (-483 4823);
FORCEPROP 2 LAST PART_TYPE SMLF
J 0
(-475 5200);
DISPLAY 0.680851 (-475 5200);
FORCEPROP 2 LAST VALUE AST2600A3-GP
J 0
(-475 5150);
DISPLAY 0.680851 (-475 5150);
FORCEPROP 1 LAST PART_NUMBER AJ026000T06
J 0
(-483 4950);
DISPLAY 0.723404 (-483 4950);
FORCEPROP 1 LAST NEEDS_NO_SIZE TRUE
J 0
(525 3950);
DISPLAY 0.723404 (525 3950);
DISPLAY INVISIBLE (525 3950);
FORCEPROP 1 LAST CDS_LMAN_SYM_OUTLINE -1025,825,1025,-825
J 0
(525 3950);
DISPLAY 0.468085 (525 3950);
PAINT GREEN (525 3950);
DISPLAY INVISIBLE (525 3950);
FORCEPROP 1 LAST PATH I149
J 0
(525 3950);
DISPLAY 0.723404 (525 3950);
DISPLAY INVISIBLE (525 3950);
FORCEPROP 2 LAST CDS_LIB pure_quanta
J 0
(525 3950);
DISPLAY INVISIBLE (525 3950);
FORCEPROP 1 LAST LOCATION U5
J 0
(-483 5097);
DISPLAY 0.723404 (-483 5097);
FORCEPROP 0 LASTPIN (-650 3925) $PN AB4
J 2
(-660 3935);
DISPLAY 0.680851 (-660 3935);
PAINT MONO (-660 3935);
FORCEPROP 0 LASTPIN (-650 3875) $PN AA4
J 2
(-660 3885);
DISPLAY 0.680851 (-660 3885);
PAINT MONO (-660 3885);
FORCEPROP 0 LASTPIN (-650 3825) $PN AC4
J 2
(-660 3835);
DISPLAY 0.680851 (-660 3835);
PAINT MONO (-660 3835);
FORCEPROP 0 LASTPIN (-650 3775) $PN AA5
J 2
(-660 3785);
DISPLAY 0.680851 (-660 3785);
PAINT MONO (-660 3785);
FORCEPROP 0 LASTPIN (-650 3725) $PN Y5
J 2
(-660 3735);
DISPLAY 0.680851 (-660 3735);
PAINT MONO (-660 3735);
FORCEPROP 0 LASTPIN (-650 3675) $PN AB5
J 2
(-660 3685);
DISPLAY 0.680851 (-660 3685);
PAINT MONO (-660 3685);
FORCEPROP 0 LASTPIN (-650 3625) $PN AC5
J 2
(-660 3635);
DISPLAY 0.680851 (-660 3635);
PAINT MONO (-660 3635);
FORCEPROP 0 LASTPIN (-650 3575) $PN AB6
J 2
(-660 3585);
DISPLAY 0.680851 (-660 3585);
PAINT MONO (-660 3585);
FORCEPROP 0 LASTPIN (1700 3725) $PN Y1
J 0
(1710 3735);
DISPLAY 0.680851 (1710 3735);
PAINT MONO (1710 3735);
FORCEPROP 0 LASTPIN (1700 3675) $PN Y2
J 0
(1710 3685);
DISPLAY 0.680851 (1710 3685);
PAINT MONO (1710 3685);
FORCEPROP 0 LASTPIN (1700 3625) $PN Y3
J 0
(1710 3635);
DISPLAY 0.680851 (1710 3635);
PAINT MONO (1710 3635);
FORCEPROP 0 LASTPIN (1700 3575) $PN Y4
J 0
(1710 3585);
DISPLAY 0.680851 (1710 3585);
PAINT MONO (1710 3585);
FORCEPROP 0 LASTPIN (-650 3425) $PN AF23
J 2
(-660 3435);
DISPLAY 0.680851 (-660 3435);
PAINT MONO (-660 3435);
FORCEPROP 0 LASTPIN (-650 3375) $PN AE24
J 2
(-660 3385);
DISPLAY 0.680851 (-660 3385);
PAINT MONO (-660 3385);
FORCEPROP 0 LASTPIN (-650 3275) $PN AF22
J 2
(-660 3285);
DISPLAY 0.680851 (-660 3285);
PAINT MONO (-660 3285);
FORCEPROP 0 LASTPIN (-650 3225) $PN AE22
J 2
(-660 3235);
DISPLAY 0.680851 (-660 3235);
PAINT MONO (-660 3235);
FORCEPROP 0 LASTPIN (1700 3425) $PN AF25
J 0
(1710 3435);
DISPLAY 0.680851 (1710 3435);
PAINT MONO (1710 3435);
FORCEPROP 0 LASTPIN (1700 3375) $PN AE26
J 0
(1710 3385);
DISPLAY 0.680851 (1710 3385);
PAINT MONO (1710 3385);
FORCEPROP 0 LASTPIN (1700 3275) $PN AE25
J 0
(1710 3285);
DISPLAY 0.680851 (1710 3285);
PAINT MONO (1710 3285);
FORCEPROP 0 LASTPIN (1700 3225) $PN AF24
J 0
(1710 3235);
DISPLAY 0.680851 (1710 3235);
PAINT MONO (1710 3235);
FORCEPROP 0 LASTPIN (-650 4675) $PN B3
J 2
(-660 4685);
DISPLAY 0.680851 (-660 4685);
PAINT MONO (-660 4685);
FORCEPROP 0 LASTPIN (-650 4625) $PN A2
J 2
(-660 4635);
DISPLAY 0.680851 (-660 4635);
PAINT MONO (-660 4635);
FORCEPROP 0 LASTPIN (-650 4575) $PN B2
J 2
(-660 4585);
DISPLAY 0.680851 (-660 4585);
PAINT MONO (-660 4585);
FORCEPROP 0 LASTPIN (-650 4525) $PN B1
J 2
(-660 4535);
DISPLAY 0.680851 (-660 4535);
PAINT MONO (-660 4535);
FORCEPROP 0 LASTPIN (-650 4475) $PN C4
J 2
(-660 4485);
DISPLAY 0.680851 (-660 4485);
PAINT MONO (-660 4485);
FORCEPROP 0 LASTPIN (-650 4425) $PN E5
J 2
(-660 4435);
DISPLAY 0.680851 (-660 4435);
PAINT MONO (-660 4435);
FORCEPROP 0 LASTPIN (1700 4675) $PN C6
J 0
(1710 4685);
DISPLAY 0.680851 (1710 4685);
PAINT MONO (1710 4685);
FORCEPROP 0 LASTPIN (1700 4625) $PN D6
J 0
(1710 4635);
DISPLAY 0.680851 (1710 4635);
PAINT MONO (1710 4635);
FORCEPROP 0 LASTPIN (1700 4575) $PN D5
J 0
(1710 4585);
DISPLAY 0.680851 (1710 4585);
PAINT MONO (1710 4585);
FORCEPROP 0 LASTPIN (1700 4525) $PN A3
J 0
(1710 4535);
DISPLAY 0.680851 (1710 4535);
PAINT MONO (1710 4535);
FORCEPROP 0 LASTPIN (1700 4475) $PN C5
J 0
(1710 4485);
DISPLAY 0.680851 (1710 4485);
PAINT MONO (1710 4485);
FORCEPROP 0 LASTPIN (1700 4425) $PN E6
J 0
(1710 4435);
DISPLAY 0.680851 (1710 4435);
PAINT MONO (1710 4435);
FORCEPROP 0 LASTPIN (-650 4275) $PN D2
J 2
(-660 4285);
DISPLAY 0.680851 (-660 4285);
PAINT MONO (-660 4285);
FORCEPROP 0 LASTPIN (-650 4225) $PN E3
J 2
(-660 4235);
DISPLAY 0.680851 (-660 4235);
PAINT MONO (-660 4235);
FORCEPROP 0 LASTPIN (-650 4175) $PN D1
J 2
(-660 4185);
DISPLAY 0.680851 (-660 4185);
PAINT MONO (-660 4185);
FORCEPROP 0 LASTPIN (-650 4125) $PN F4
J 2
(-660 4135);
DISPLAY 0.680851 (-660 4135);
PAINT MONO (-660 4135);
FORCEPROP 0 LASTPIN (-650 4075) $PN E2
J 2
(-660 4085);
DISPLAY 0.680851 (-660 4085);
PAINT MONO (-660 4085);
FORCEPROP 0 LASTPIN (-650 4025) $PN E1
J 2
(-660 4035);
DISPLAY 0.680851 (-660 4035);
PAINT MONO (-660 4035);
FORCEPROP 0 LASTPIN (1700 4275) $PN D4
J 0
(1710 4285);
DISPLAY 0.680851 (1710 4285);
PAINT MONO (1710 4285);
FORCEPROP 0 LASTPIN (1700 4225) $PN C2
J 0
(1710 4235);
DISPLAY 0.680851 (1710 4235);
PAINT MONO (1710 4235);
FORCEPROP 0 LASTPIN (1700 4175) $PN C1
J 0
(1710 4185);
DISPLAY 0.680851 (1710 4185);
PAINT MONO (1710 4185);
FORCEPROP 0 LASTPIN (1700 4125) $PN D3
J 0
(1710 4135);
DISPLAY 0.680851 (1710 4135);
PAINT MONO (1710 4135);
FORCEPROP 0 LASTPIN (1700 4075) $PN E4
J 0
(1710 4085);
DISPLAY 0.680851 (1710 4085);
PAINT MONO (1710 4085);
FORCEPROP 0 LASTPIN (1700 4025) $PN F5
J 0
(1710 4035);
DISPLAY 0.680851 (1710 4035);
PAINT MONO (1710 4035);
FORCEPROP 0 LAST $SEC 3
J 0
(-475 5250);
DISPLAY 0.680851 (-475 5250);
PAINT MONO (-475 5250);
DISPLAY INVISIBLE (-475 5250);
FORCEPROP 0 LAST CDS_SEC 3
J 0
(-475 5250);
DISPLAY 0.680851 (-475 5250);
DISPLAY INVISIBLE (-475 5250);
FORCEADD UNIVERSAL_GND..1
(-2975 650);
FORCEPROP 3 LASTPIN (-2975 700) SIG_NAME GND\g
J 0
(-2965 710);
DISPLAY 0.659574 (-2965 710);
PAINT MONO (-2965 710);
DISPLAY INVISIBLE (-2965 710);
FORCEPROP 1 LAST PATH I162
J 0
(-2900 650);
DISPLAY 0.872340 (-2900 650);
PAINT AQUA (-2900 650);
DISPLAY INVISIBLE (-2900 650);
FORCEPROP 2 LAST CDS_LIB logical_power
J 0
(-2975 650);
DISPLAY INVISIBLE (-2975 650);
FORCEPROP 1 LAST HDL_POWER GND
J 1
(-2950 575);
DISPLAY 0.702128 (-2950 575);
PAINT GREEN (-2950 575);
DISPLAY INVISIBLE (-2950 575);
FORCEADD Q_RES..2
(-3100 975);
FORCEPROP 1 LAST WATTAGE 1/16W
J 0
(-3060 950);
DISPLAY 0.510638 (-3060 950);
PAINT SKYBLUE (-3060 950);
FORCEPROP 1 LAST PACK_TYPE 0402LF
J 0
(-3075 850);
DISPLAY 0.510638 (-3075 850);
PAINT SKYBLUE (-3075 850);
FORCEPROP 1 LAST MATERIAL EMPTY
J 0
(-3060 900);
DISPLAY 0.510638 (-3060 900);
PAINT RED (-3060 900);
FORCEPROP 1 LAST TOLERANCE 1%
J 0
(-3055 1000);
DISPLAY 0.510638 (-3055 1000);
PAINT SKYBLUE (-3055 1000);
FORCEPROP 1 LAST VALUE 1K
J 0
(-3055 1050);
DISPLAY 0.510638 (-3055 1050);
PAINT SKYBLUE (-3055 1050);
FORCEPROP 1 LAST PATH I163
J 0
(-3050 1150);
DISPLAY 0.978723 (-3050 1150);
PAINT WHITE (-3050 1150);
DISPLAY INVISIBLE (-3050 1150);
FORCEPROP 2 LAST SEC_TYPE 0402LF
J 0
(-3050 1200);
DISPLAY 0.680851 (-3050 1200);
DISPLAY INVISIBLE (-3050 1200);
FORCEPROP 2 LAST CDS_LIB pure_quanta
J 0
(-3100 975);
DISPLAY INVISIBLE (-3100 975);
FORCEPROP 1 LAST PART_NUMBER TMP_QCS21002FB24
J 0
(-3060 850);
DISPLAY 0.510638 (-3060 850);
PAINT WHITE (-3060 850);
DISPLAY INVISIBLE (-3060 850);
FORCEPROP 1 LAST LOCATION R684
J 0
(-3055 1100);
DISPLAY 0.702128 (-3055 1100);
PAINT YELLOW (-3055 1100);
FORCEPROP 1 LASTPIN (-3100 1075) $PN 1
J 0
(-3095 1037);
DISPLAY 0.808511 (-3095 1037);
PAINT WHITE (-3095 1037);
FORCEPROP 1 LASTPIN (-3100 875) $PN 2
J 0
(-3095 885);
DISPLAY 0.808511 (-3095 885);
PAINT WHITE (-3095 885);
FORCEPROP 2 LAST SEC 1
J 0
(-3050 1200);
DISPLAY 0.680851 (-3050 1200);
PAINT MONO (-3050 1200);
DISPLAY INVISIBLE (-3050 1200);
FORCEADD Q_RES..2
(-3100 1600);
FORCEPROP 1 LAST TOLERANCE 1%
J 0
(-3075 1600);
DISPLAY 0.510638 (-3075 1600);
PAINT SKYBLUE (-3075 1600);
FORCEPROP 1 LAST VALUE 4.7K
J 0
(-3075 1650);
DISPLAY 0.510638 (-3075 1650);
PAINT SKYBLUE (-3075 1650);
FORCEPROP 1 LAST PACK_TYPE 0402LF
J 0
(-3075 1475);
DISPLAY 0.510638 (-3075 1475);
PAINT SKYBLUE (-3075 1475);
FORCEPROP 1 LAST MATERIAL EMPTY
J 0
(-3075 1500);
DISPLAY 0.510638 (-3075 1500);
PAINT RED (-3075 1500);
FORCEPROP 1 LAST WATTAGE 1/16W
J 0
(-3075 1550);
DISPLAY 0.510638 (-3075 1550);
PAINT SKYBLUE (-3075 1550);
FORCEPROP 1 LAST PART_NUMBER CS24702FB10
J 0
(-3060 1475);
DISPLAY 0.510638 (-3060 1475);
PAINT WHITE (-3060 1475);
DISPLAY INVISIBLE (-3060 1475);
FORCEPROP 1 LAST PATH I164
J 0
(-3050 1775);
DISPLAY 0.978723 (-3050 1775);
PAINT WHITE (-3050 1775);
DISPLAY INVISIBLE (-3050 1775);
FORCEPROP 2 LAST CDS_LIB pure_quanta
J 0
(-3100 1600);
DISPLAY INVISIBLE (-3100 1600);
FORCEPROP 1 LAST LOCATION R686
J 0
(-3055 1725);
DISPLAY 0.702128 (-3055 1725);
PAINT YELLOW (-3055 1725);
FORCEPROP 1 LASTPIN (-3100 1700) $PN 1
J 0
(-3095 1662);
DISPLAY 0.808511 (-3095 1662);
PAINT WHITE (-3095 1662);
FORCEPROP 1 LASTPIN (-3100 1500) $PN 2
J 0
(-3095 1510);
DISPLAY 0.808511 (-3095 1510);
PAINT WHITE (-3095 1510);
FORCEPROP 0 LAST $SEC 1
J 0
(-3050 1775);
DISPLAY 0.680851 (-3050 1775);
PAINT MONO (-3050 1775);
DISPLAY INVISIBLE (-3050 1775);
FORCEPROP 0 LAST CDS_SEC 1
J 0
(-3050 1775);
DISPLAY 0.680851 (-3050 1775);
DISPLAY INVISIBLE (-3050 1775);
FORCEADD Q_RES..2
(-2875 975);
FORCEPROP 1 LAST PACK_TYPE 0402LF
J 0
(-2835 800);
DISPLAY 0.510638 (-2835 800);
PAINT SKYBLUE (-2835 800);
FORCEPROP 1 LAST PART_NUMBER TMP_QCS21002FB24
J 0
(-2835 850);
DISPLAY 0.510638 (-2835 850);
PAINT WHITE (-2835 850);
FORCEPROP 1 LAST TOLERANCE 1%
J 0
(-2830 1000);
DISPLAY 0.510638 (-2830 1000);
PAINT SKYBLUE (-2830 1000);
FORCEPROP 1 LAST WATTAGE 1/16W
J 0
(-2835 950);
DISPLAY 0.510638 (-2835 950);
PAINT SKYBLUE (-2835 950);
FORCEPROP 1 LAST MATERIAL EMPTY
J 0
(-2835 900);
DISPLAY 0.510638 (-2835 900);
PAINT RED (-2835 900);
FORCEPROP 1 LAST VALUE 1K
J 0
(-2830 1050);
DISPLAY 0.510638 (-2830 1050);
PAINT SKYBLUE (-2830 1050);
FORCEPROP 1 LAST PATH I165
J 0
(-2825 1150);
DISPLAY 0.978723 (-2825 1150);
PAINT WHITE (-2825 1150);
DISPLAY INVISIBLE (-2825 1150);
FORCEPROP 2 LAST CDS_LIB pure_quanta
J 0
(-2875 975);
DISPLAY INVISIBLE (-2875 975);
FORCEPROP 2 LAST SEC_TYPE 0402LF
J 0
(-2825 1200);
DISPLAY 0.680851 (-2825 1200);
DISPLAY INVISIBLE (-2825 1200);
FORCEPROP 1 LAST LOCATION R685
J 0
(-2830 1100);
DISPLAY 0.702128 (-2830 1100);
PAINT YELLOW (-2830 1100);
FORCEPROP 1 LASTPIN (-2875 1075) $PN 1
J 0
(-2870 1037);
DISPLAY 0.808511 (-2870 1037);
PAINT WHITE (-2870 1037);
FORCEPROP 1 LASTPIN (-2875 875) $PN 2
J 0
(-2870 885);
DISPLAY 0.808511 (-2870 885);
PAINT WHITE (-2870 885);
FORCEPROP 2 LAST SEC 1
J 0
(-2825 1200);
DISPLAY 0.680851 (-2825 1200);
PAINT MONO (-2825 1200);
DISPLAY INVISIBLE (-2825 1200);
FORCEADD Q_RES..2
(-2875 1600);
FORCEPROP 1 LAST PART_NUMBER CS24702FB10
J 0
(-2850 1475);
DISPLAY 0.510638 (-2850 1475);
PAINT WHITE (-2850 1475);
FORCEPROP 1 LAST PACK_TYPE 0402LF
J 0
(-2835 1425);
DISPLAY 0.510638 (-2835 1425);
PAINT SKYBLUE (-2835 1425);
FORCEPROP 1 LAST TOLERANCE 1%
J 0
(-2830 1625);
DISPLAY 0.510638 (-2830 1625);
PAINT SKYBLUE (-2830 1625);
FORCEPROP 1 LAST WATTAGE 1/16W
J 0
(-2835 1575);
DISPLAY 0.510638 (-2835 1575);
PAINT SKYBLUE (-2835 1575);
FORCEPROP 1 LAST MATERIAL EMPTY
J 0
(-2835 1525);
DISPLAY 0.510638 (-2835 1525);
PAINT RED (-2835 1525);
FORCEPROP 1 LAST VALUE 4.7K
J 0
(-2830 1675);
DISPLAY 0.510638 (-2830 1675);
PAINT SKYBLUE (-2830 1675);
FORCEPROP 1 LAST PATH I166
J 0
(-2825 1775);
DISPLAY 0.978723 (-2825 1775);
PAINT WHITE (-2825 1775);
DISPLAY INVISIBLE (-2825 1775);
FORCEPROP 2 LAST CDS_LIB pure_quanta
J 0
(-2875 1600);
DISPLAY INVISIBLE (-2875 1600);
FORCEPROP 1 LAST LOCATION R687
J 0
(-2830 1725);
DISPLAY 0.702128 (-2830 1725);
PAINT YELLOW (-2830 1725);
FORCEPROP 1 LASTPIN (-2875 1700) $PN 1
J 0
(-2870 1662);
DISPLAY 0.808511 (-2870 1662);
PAINT WHITE (-2870 1662);
FORCEPROP 1 LASTPIN (-2875 1500) $PN 2
J 0
(-2870 1510);
DISPLAY 0.808511 (-2870 1510);
PAINT WHITE (-2870 1510);
FORCEPROP 0 LAST $SEC 1
J 0
(-2825 1775);
DISPLAY 0.680851 (-2825 1775);
PAINT MONO (-2825 1775);
DISPLAY INVISIBLE (-2825 1775);
FORCEPROP 0 LAST CDS_SEC 1
J 0
(-2825 1775);
DISPLAY 0.680851 (-2825 1775);
DISPLAY INVISIBLE (-2825 1775);
FORCEADD OFFPAGE..3
(-2025 1350);
FORCEPROP 2 LAST $XR0 12 
J 0
(-1811 1350);
DISPLAY 0.638298 (-1811 1350);
PAINT MONO (-1811 1350);
FORCEPROP 2 LAST PATH I167
J 0
(-1800 1400);
DISPLAY 0.680851 (-1800 1400);
DISPLAY INVISIBLE (-1800 1400);
FORCEPROP 2 LAST CDS_LIB standard
J 0
(-2025 1350);
DISPLAY INVISIBLE (-2025 1350);
FORCEPROP 1 LAST OFFPAGE TRUE
J 0
(-1700 1225);
DISPLAY 0.872340 (-1700 1225);
PAINT GREEN (-1700 1225);
DISPLAY INVISIBLE (-1700 1225);
FORCEPROP 1 LAST COMMENT_BODY TRUE
J 0
(-2075 1250);
DISPLAY 0.872340 (-2075 1250);
PAINT PEACH (-2075 1250);
DISPLAY INVISIBLE (-2075 1250);
FORCEADD OFFPAGE..3
(-2025 1400);
FORCEPROP 2 LAST $XR0 12 
J 0
(-1811 1400);
DISPLAY 0.638298 (-1811 1400);
PAINT MONO (-1811 1400);
FORCEPROP 2 LAST PATH I168
J 0
(-1800 1450);
DISPLAY 0.680851 (-1800 1450);
DISPLAY INVISIBLE (-1800 1450);
FORCEPROP 2 LAST CDS_LIB standard
J 0
(-2025 1400);
DISPLAY INVISIBLE (-2025 1400);
FORCEPROP 1 LAST OFFPAGE TRUE
J 0
(-1700 1275);
DISPLAY 0.872340 (-1700 1275);
PAINT GREEN (-1700 1275);
DISPLAY INVISIBLE (-1700 1275);
FORCEPROP 1 LAST COMMENT_BODY TRUE
J 0
(-2075 1300);
DISPLAY 0.872340 (-2075 1300);
PAINT PEACH (-2075 1300);
DISPLAY INVISIBLE (-2075 1300);
FORCEADD Q_RES..1
(-275 2200);
FORCEPROP 1 LAST PACK_TYPE 0402LF
J 0
(-225 2150);
DISPLAY 0.510638 (-225 2150);
PAINT SKYBLUE (-225 2150);
FORCEPROP 1 LAST VALUE 1K
J 2
(0 2200);
DISPLAY 0.510638 (0 2200);
PAINT SKYBLUE (0 2200);
FORCEPROP 1 LAST WATTAGE 1/16W
J 2
(-350 2150);
DISPLAY 0.510638 (-350 2150);
PAINT SKYBLUE (-350 2150);
FORCEPROP 1 LAST TOLERANCE 1%
J 0
(-325 2150);
DISPLAY 0.510638 (-325 2150);
PAINT SKYBLUE (-325 2150);
FORCEPROP 1 LAST MATERIAL CHIP
J 0
(75 2200);
DISPLAY 0.510638 (75 2200);
PAINT SKYBLUE (75 2200);
FORCEPROP 1 LAST PART_NUMBER CS21002FB06
J 0
(-325 2300);
DISPLAY 0.510638 (-325 2300);
PAINT WHITE (-325 2300);
DISPLAY INVISIBLE (-325 2300);
FORCEPROP 1 LAST PATH I171
J 0
(-325 2350);
DISPLAY 0.978723 (-325 2350);
PAINT WHITE (-325 2350);
DISPLAY INVISIBLE (-325 2350);
FORCEPROP 2 LAST CDS_LIB pure_quanta
J 0
(-275 2200);
DISPLAY INVISIBLE (-275 2200);
FORCEPROP 1 LAST LOCATION R194
J 0
(-575 2200);
DISPLAY 0.702128 (-575 2200);
PAINT YELLOW (-575 2200);
FORCEPROP 1 LASTPIN (-375 2200) $PN 1
J 0
(-363 2212);
DISPLAY 0.787234 (-363 2212);
PAINT MONO (-363 2212);
FORCEPROP 1 LASTPIN (-175 2200) $PN 2
J 0
(-213 2212);
DISPLAY 0.787234 (-213 2212);
PAINT MONO (-213 2212);
FORCEPROP 0 LAST $SEC 1
J 0
(-575 2250);
DISPLAY 0.680851 (-575 2250);
PAINT MONO (-575 2250);
DISPLAY INVISIBLE (-575 2250);
FORCEPROP 0 LAST CDS_SEC 1
J 0
(-575 2250);
DISPLAY 0.680851 (-575 2250);
DISPLAY INVISIBLE (-575 2250);
FORCEADD Q_RES..1
(-275 2100);
FORCEPROP 1 LAST TOLERANCE 1%
J 0
(-325 2050);
DISPLAY 0.510638 (-325 2050);
PAINT SKYBLUE (-325 2050);
FORCEPROP 1 LAST MATERIAL CHIP
J 0
(75 2100);
DISPLAY 0.510638 (75 2100);
PAINT SKYBLUE (75 2100);
FORCEPROP 1 LAST WATTAGE 1/16W
J 2
(-350 2050);
DISPLAY 0.510638 (-350 2050);
PAINT SKYBLUE (-350 2050);
FORCEPROP 1 LAST PACK_TYPE 0402LF
J 0
(-225 2050);
DISPLAY 0.510638 (-225 2050);
PAINT SKYBLUE (-225 2050);
FORCEPROP 1 LAST VALUE 1K
J 2
(0 2100);
DISPLAY 0.510638 (0 2100);
PAINT SKYBLUE (0 2100);
FORCEPROP 2 LAST CDS_LIB pure_quanta
J 0
(-275 2100);
DISPLAY INVISIBLE (-275 2100);
FORCEPROP 1 LAST PATH I172
J 0
(-325 2250);
DISPLAY 0.978723 (-325 2250);
PAINT WHITE (-325 2250);
DISPLAY INVISIBLE (-325 2250);
FORCEPROP 1 LAST PART_NUMBER CS21002FB06
J 0
(-325 2200);
DISPLAY 0.510638 (-325 2200);
PAINT WHITE (-325 2200);
DISPLAY INVISIBLE (-325 2200);
FORCEPROP 1 LAST LOCATION R195
J 0
(-575 2100);
DISPLAY 0.702128 (-575 2100);
PAINT YELLOW (-575 2100);
FORCEPROP 1 LASTPIN (-375 2100) $PN 1
J 0
(-363 2112);
DISPLAY 0.787234 (-363 2112);
PAINT MONO (-363 2112);
FORCEPROP 1 LASTPIN (-175 2100) $PN 2
J 0
(-213 2112);
DISPLAY 0.787234 (-213 2112);
PAINT MONO (-213 2112);
FORCEPROP 0 LAST $SEC 1
J 0
(-575 2150);
DISPLAY 0.680851 (-575 2150);
PAINT MONO (-575 2150);
DISPLAY INVISIBLE (-575 2150);
FORCEPROP 0 LAST CDS_SEC 1
J 0
(-575 2150);
DISPLAY 0.680851 (-575 2150);
DISPLAY INVISIBLE (-575 2150);
FORCEADD Q_RES..1
(-275 2000);
FORCEPROP 1 LAST PACK_TYPE 0402LF
J 0
(-225 1950);
DISPLAY 0.510638 (-225 1950);
PAINT SKYBLUE (-225 1950);
FORCEPROP 1 LAST MATERIAL CHIP
J 0
(75 2000);
DISPLAY 0.510638 (75 2000);
PAINT SKYBLUE (75 2000);
FORCEPROP 1 LAST WATTAGE 1/16W
J 2
(-350 1950);
DISPLAY 0.510638 (-350 1950);
PAINT SKYBLUE (-350 1950);
FORCEPROP 1 LAST TOLERANCE 1%
J 0
(-325 1950);
DISPLAY 0.510638 (-325 1950);
PAINT SKYBLUE (-325 1950);
FORCEPROP 1 LAST VALUE 1K
J 2
(0 2000);
DISPLAY 0.510638 (0 2000);
PAINT SKYBLUE (0 2000);
FORCEPROP 2 LAST CDS_LIB pure_quanta
J 0
(-275 2000);
DISPLAY INVISIBLE (-275 2000);
FORCEPROP 1 LAST PATH I173
J 0
(-325 2150);
DISPLAY 0.978723 (-325 2150);
PAINT WHITE (-325 2150);
DISPLAY INVISIBLE (-325 2150);
FORCEPROP 1 LAST PART_NUMBER CS21002FB06
J 0
(-325 2100);
DISPLAY 0.510638 (-325 2100);
PAINT WHITE (-325 2100);
DISPLAY INVISIBLE (-325 2100);
FORCEPROP 1 LAST LOCATION R190
J 0
(-575 2000);
DISPLAY 0.702128 (-575 2000);
PAINT YELLOW (-575 2000);
FORCEPROP 1 LASTPIN (-375 2000) $PN 1
J 0
(-363 2012);
DISPLAY 0.787234 (-363 2012);
PAINT MONO (-363 2012);
FORCEPROP 1 LASTPIN (-175 2000) $PN 2
J 0
(-213 2012);
DISPLAY 0.787234 (-213 2012);
PAINT MONO (-213 2012);
FORCEPROP 0 LAST $SEC 1
J 0
(-575 2050);
DISPLAY 0.680851 (-575 2050);
PAINT MONO (-575 2050);
DISPLAY INVISIBLE (-575 2050);
FORCEPROP 0 LAST CDS_SEC 1
J 0
(-575 2050);
DISPLAY 0.680851 (-575 2050);
DISPLAY INVISIBLE (-575 2050);
FORCEADD Q_RES..1
(-275 1900);
FORCEPROP 1 LAST PACK_TYPE 0402LF
J 0
(-225 1850);
DISPLAY 0.510638 (-225 1850);
PAINT SKYBLUE (-225 1850);
FORCEPROP 1 LAST MATERIAL CHIP
J 0
(75 1900);
DISPLAY 0.510638 (75 1900);
PAINT SKYBLUE (75 1900);
FORCEPROP 1 LAST WATTAGE 1/16W
J 2
(-350 1850);
DISPLAY 0.510638 (-350 1850);
PAINT SKYBLUE (-350 1850);
FORCEPROP 1 LAST VALUE 1K
J 2
(0 1900);
DISPLAY 0.510638 (0 1900);
PAINT SKYBLUE (0 1900);
FORCEPROP 1 LAST TOLERANCE 1%
J 0
(-325 1850);
DISPLAY 0.510638 (-325 1850);
PAINT SKYBLUE (-325 1850);
FORCEPROP 1 LAST PART_NUMBER CS21002FB06
J 0
(-325 2000);
DISPLAY 0.510638 (-325 2000);
PAINT WHITE (-325 2000);
DISPLAY INVISIBLE (-325 2000);
FORCEPROP 1 LAST PATH I174
J 0
(-325 2050);
DISPLAY 0.978723 (-325 2050);
PAINT WHITE (-325 2050);
DISPLAY INVISIBLE (-325 2050);
FORCEPROP 2 LAST CDS_LIB pure_quanta
J 0
(-275 1900);
DISPLAY INVISIBLE (-275 1900);
FORCEPROP 1 LAST LOCATION R191
J 0
(-575 1900);
DISPLAY 0.702128 (-575 1900);
PAINT YELLOW (-575 1900);
FORCEPROP 1 LASTPIN (-375 1900) $PN 1
J 0
(-363 1912);
DISPLAY 0.787234 (-363 1912);
PAINT MONO (-363 1912);
FORCEPROP 1 LASTPIN (-175 1900) $PN 2
J 0
(-213 1912);
DISPLAY 0.787234 (-213 1912);
PAINT MONO (-213 1912);
FORCEPROP 0 LAST $SEC 1
J 0
(-575 1950);
DISPLAY 0.680851 (-575 1950);
PAINT MONO (-575 1950);
DISPLAY INVISIBLE (-575 1950);
FORCEPROP 0 LAST CDS_SEC 1
J 0
(-575 1950);
DISPLAY 0.680851 (-575 1950);
DISPLAY INVISIBLE (-575 1950);
FORCEADD Q_RES..1
(-275 1800);
FORCEPROP 1 LAST MATERIAL CHIP
J 0
(75 1800);
DISPLAY 0.510638 (75 1800);
PAINT SKYBLUE (75 1800);
FORCEPROP 1 LAST PACK_TYPE 0402LF
J 0
(-225 1750);
DISPLAY 0.510638 (-225 1750);
PAINT SKYBLUE (-225 1750);
FORCEPROP 1 LAST TOLERANCE 1%
J 0
(-325 1750);
DISPLAY 0.510638 (-325 1750);
PAINT SKYBLUE (-325 1750);
FORCEPROP 1 LAST WATTAGE 1/16W
J 2
(-350 1750);
DISPLAY 0.510638 (-350 1750);
PAINT SKYBLUE (-350 1750);
FORCEPROP 1 LAST VALUE 1K
J 2
(0 1800);
DISPLAY 0.510638 (0 1800);
PAINT SKYBLUE (0 1800);
FORCEPROP 1 LAST PATH I183
J 0
(-325 1950);
DISPLAY 0.978723 (-325 1950);
PAINT WHITE (-325 1950);
DISPLAY INVISIBLE (-325 1950);
FORCEPROP 2 LAST CDS_LIB pure_quanta
J 0
(-275 1800);
DISPLAY INVISIBLE (-275 1800);
FORCEPROP 1 LAST PART_NUMBER CS21002FB06
J 0
(-325 1900);
DISPLAY 0.510638 (-325 1900);
PAINT WHITE (-325 1900);
DISPLAY INVISIBLE (-325 1900);
FORCEPROP 1 LAST LOCATION R188
J 0
(-575 1800);
DISPLAY 0.702128 (-575 1800);
PAINT YELLOW (-575 1800);
FORCEPROP 1 LASTPIN (-375 1800) $PN 1
J 0
(-363 1812);
DISPLAY 0.787234 (-363 1812);
PAINT MONO (-363 1812);
FORCEPROP 1 LASTPIN (-175 1800) $PN 2
J 0
(-213 1812);
DISPLAY 0.787234 (-213 1812);
PAINT MONO (-213 1812);
FORCEPROP 0 LAST $SEC 1
J 0
(-575 1850);
DISPLAY 0.680851 (-575 1850);
PAINT MONO (-575 1850);
DISPLAY INVISIBLE (-575 1850);
FORCEPROP 0 LAST CDS_SEC 1
J 0
(-575 1850);
DISPLAY 0.680851 (-575 1850);
DISPLAY INVISIBLE (-575 1850);
FORCEADD OFFPAGE..2
(1375 1800);
FORCEPROP 2 LAST $XR1 10 
J 0
(1654 1800);
DISPLAY 0.638298 (1654 1800);
PAINT MONO (1654 1800);
FORCEPROP 2 LAST $XR0 14 
J 0
(1564 1800);
DISPLAY 0.638298 (1564 1800);
PAINT MONO (1564 1800);
FORCEPROP 2 LAST PATH I184
J 0
(1675 1850);
DISPLAY 0.680851 (1675 1850);
DISPLAY INVISIBLE (1675 1850);
FORCEPROP 2 LAST CDS_LIB standard
J 0
(1375 1800);
DISPLAY INVISIBLE (1375 1800);
FORCEPROP 1 LAST OFFPAGE TRUE
J 0
(1700 1675);
DISPLAY 0.872340 (1700 1675);
PAINT GREEN (1700 1675);
DISPLAY INVISIBLE (1700 1675);
FORCEPROP 1 LAST COMMENT_BODY TRUE
J 0
(1330 1705);
DISPLAY 0.872340 (1330 1705);
PAINT PEACH (1330 1705);
DISPLAY INVISIBLE (1330 1705);
FORCEADD OFFPAGE..2
(1375 1700);
FORCEPROP 2 LAST $XR1 14 
J 0
(1654 1700);
DISPLAY 0.638298 (1654 1700);
PAINT MONO (1654 1700);
FORCEPROP 2 LAST $XR0 10 
J 0
(1564 1700);
DISPLAY 0.638298 (1564 1700);
PAINT MONO (1564 1700);
FORCEPROP 2 LAST PATH I185
J 0
(1675 1750);
DISPLAY 0.680851 (1675 1750);
DISPLAY INVISIBLE (1675 1750);
FORCEPROP 2 LAST CDS_LIB standard
J 0
(1375 1700);
DISPLAY INVISIBLE (1375 1700);
FORCEPROP 1 LAST OFFPAGE TRUE
J 0
(1700 1575);
DISPLAY 0.872340 (1700 1575);
PAINT GREEN (1700 1575);
DISPLAY INVISIBLE (1700 1575);
FORCEPROP 1 LAST COMMENT_BODY TRUE
J 0
(1330 1605);
DISPLAY 0.872340 (1330 1605);
PAINT PEACH (1330 1605);
DISPLAY INVISIBLE (1330 1605);
FORCEADD OFFPAGE..2
(1375 1575);
FORCEPROP 2 LAST $XR0 14 
J 0
(1564 1575);
DISPLAY 0.638298 (1564 1575);
PAINT MONO (1564 1575);
FORCEPROP 2 LAST $XR1 10 
J 0
(1654 1575);
DISPLAY 0.638298 (1654 1575);
PAINT MONO (1654 1575);
FORCEPROP 2 LAST PATH I186
J 0
(1675 1625);
DISPLAY 0.680851 (1675 1625);
DISPLAY INVISIBLE (1675 1625);
FORCEPROP 2 LAST CDS_LIB standard
J 0
(1375 1575);
DISPLAY INVISIBLE (1375 1575);
FORCEPROP 1 LAST OFFPAGE TRUE
J 0
(1700 1450);
DISPLAY 0.872340 (1700 1450);
PAINT GREEN (1700 1450);
DISPLAY INVISIBLE (1700 1450);
FORCEPROP 1 LAST COMMENT_BODY TRUE
J 0
(1330 1480);
DISPLAY 0.872340 (1330 1480);
PAINT PEACH (1330 1480);
DISPLAY INVISIBLE (1330 1480);
FORCEADD OFFPAGE..2
(1375 1475);
FORCEPROP 2 LAST $XR0 10 
J 0
(1564 1475);
DISPLAY 0.638298 (1564 1475);
PAINT MONO (1564 1475);
FORCEPROP 2 LAST $XR1 14 
J 0
(1654 1475);
DISPLAY 0.638298 (1654 1475);
PAINT MONO (1654 1475);
FORCEPROP 2 LAST PATH I187
J 0
(1675 1525);
DISPLAY 0.680851 (1675 1525);
DISPLAY INVISIBLE (1675 1525);
FORCEPROP 2 LAST CDS_LIB standard
J 0
(1375 1475);
DISPLAY INVISIBLE (1375 1475);
FORCEPROP 1 LAST OFFPAGE TRUE
J 0
(1700 1350);
DISPLAY 0.872340 (1700 1350);
PAINT GREEN (1700 1350);
DISPLAY INVISIBLE (1700 1350);
FORCEPROP 1 LAST COMMENT_BODY TRUE
J 0
(1330 1380);
DISPLAY 0.872340 (1330 1380);
PAINT PEACH (1330 1380);
DISPLAY INVISIBLE (1330 1380);
FORCEADD Q_RES..1
(-275 1700);
FORCEPROP 1 LAST MATERIAL CHIP
J 0
(75 1700);
DISPLAY 0.510638 (75 1700);
PAINT SKYBLUE (75 1700);
FORCEPROP 1 LAST PACK_TYPE 0402LF
J 0
(-225 1650);
DISPLAY 0.510638 (-225 1650);
PAINT SKYBLUE (-225 1650);
FORCEPROP 1 LAST TOLERANCE 1%
J 0
(-325 1650);
DISPLAY 0.510638 (-325 1650);
PAINT SKYBLUE (-325 1650);
FORCEPROP 1 LAST WATTAGE 1/16W
J 2
(-350 1650);
DISPLAY 0.510638 (-350 1650);
PAINT SKYBLUE (-350 1650);
FORCEPROP 1 LAST VALUE 1K
J 2
(0 1700);
DISPLAY 0.510638 (0 1700);
PAINT SKYBLUE (0 1700);
FORCEPROP 1 LAST PATH I188
J 0
(-325 1850);
DISPLAY 0.978723 (-325 1850);
PAINT WHITE (-325 1850);
DISPLAY INVISIBLE (-325 1850);
FORCEPROP 2 LAST CDS_LIB pure_quanta
J 0
(-275 1700);
DISPLAY INVISIBLE (-275 1700);
FORCEPROP 1 LAST PART_NUMBER CS21002FB06
J 0
(-325 1800);
DISPLAY 0.510638 (-325 1800);
PAINT WHITE (-325 1800);
DISPLAY INVISIBLE (-325 1800);
FORCEPROP 1 LAST LOCATION R189
J 0
(-575 1700);
DISPLAY 0.702128 (-575 1700);
PAINT YELLOW (-575 1700);
FORCEPROP 1 LASTPIN (-375 1700) $PN 1
J 0
(-363 1712);
DISPLAY 0.787234 (-363 1712);
PAINT MONO (-363 1712);
FORCEPROP 1 LASTPIN (-175 1700) $PN 2
J 0
(-213 1712);
DISPLAY 0.787234 (-213 1712);
PAINT MONO (-213 1712);
FORCEPROP 0 LAST $SEC 1
J 0
(-575 1750);
DISPLAY 0.680851 (-575 1750);
PAINT MONO (-575 1750);
DISPLAY INVISIBLE (-575 1750);
FORCEPROP 0 LAST CDS_SEC 1
J 0
(-575 1750);
DISPLAY 0.680851 (-575 1750);
DISPLAY INVISIBLE (-575 1750);
FORCEADD Q_RES..1
(-275 1575);
FORCEPROP 1 LAST MATERIAL CHIP
J 0
(75 1575);
DISPLAY 0.510638 (75 1575);
PAINT SKYBLUE (75 1575);
FORCEPROP 1 LAST PACK_TYPE 0402LF
J 0
(-225 1525);
DISPLAY 0.510638 (-225 1525);
PAINT SKYBLUE (-225 1525);
FORCEPROP 1 LAST VALUE 1K
J 2
(0 1575);
DISPLAY 0.510638 (0 1575);
PAINT SKYBLUE (0 1575);
FORCEPROP 1 LAST TOLERANCE 1%
J 0
(-325 1525);
DISPLAY 0.510638 (-325 1525);
PAINT SKYBLUE (-325 1525);
FORCEPROP 1 LAST WATTAGE 1/16W
J 2
(-350 1525);
DISPLAY 0.510638 (-350 1525);
PAINT SKYBLUE (-350 1525);
FORCEPROP 1 LAST PATH I189
J 0
(-325 1725);
DISPLAY 0.978723 (-325 1725);
PAINT WHITE (-325 1725);
DISPLAY INVISIBLE (-325 1725);
FORCEPROP 2 LAST CDS_LIB pure_quanta
J 0
(-275 1575);
DISPLAY INVISIBLE (-275 1575);
FORCEPROP 1 LAST PART_NUMBER CS21002FB06
J 0
(-325 1675);
DISPLAY 0.510638 (-325 1675);
PAINT WHITE (-325 1675);
DISPLAY INVISIBLE (-325 1675);
FORCEPROP 1 LAST LOCATION R196
J 0
(-575 1575);
DISPLAY 0.702128 (-575 1575);
PAINT YELLOW (-575 1575);
FORCEPROP 1 LASTPIN (-375 1575) $PN 1
J 0
(-363 1587);
DISPLAY 0.787234 (-363 1587);
PAINT MONO (-363 1587);
FORCEPROP 1 LASTPIN (-175 1575) $PN 2
J 0
(-213 1587);
DISPLAY 0.787234 (-213 1587);
PAINT MONO (-213 1587);
FORCEPROP 0 LAST $SEC 1
J 0
(-575 1625);
DISPLAY 0.680851 (-575 1625);
PAINT MONO (-575 1625);
DISPLAY INVISIBLE (-575 1625);
FORCEPROP 0 LAST CDS_SEC 1
J 0
(-575 1625);
DISPLAY 0.680851 (-575 1625);
DISPLAY INVISIBLE (-575 1625);
FORCEADD Q_RES..1
(-275 1475);
FORCEPROP 1 LAST MATERIAL CHIP
J 0
(75 1475);
DISPLAY 0.510638 (75 1475);
PAINT SKYBLUE (75 1475);
FORCEPROP 1 LAST VALUE 1K
J 2
(0 1475);
DISPLAY 0.510638 (0 1475);
PAINT SKYBLUE (0 1475);
FORCEPROP 1 LAST TOLERANCE 1%
J 0
(-325 1425);
DISPLAY 0.510638 (-325 1425);
PAINT SKYBLUE (-325 1425);
FORCEPROP 1 LAST PACK_TYPE 0402LF
J 0
(-225 1425);
DISPLAY 0.510638 (-225 1425);
PAINT SKYBLUE (-225 1425);
FORCEPROP 1 LAST WATTAGE 1/16W
J 2
(-350 1425);
DISPLAY 0.510638 (-350 1425);
PAINT SKYBLUE (-350 1425);
FORCEPROP 1 LAST PATH I190
J 0
(-325 1625);
DISPLAY 0.978723 (-325 1625);
PAINT WHITE (-325 1625);
DISPLAY INVISIBLE (-325 1625);
FORCEPROP 2 LAST CDS_LIB pure_quanta
J 0
(-275 1475);
DISPLAY INVISIBLE (-275 1475);
FORCEPROP 1 LAST PART_NUMBER CS21002FB06
J 0
(-325 1575);
DISPLAY 0.510638 (-325 1575);
PAINT WHITE (-325 1575);
DISPLAY INVISIBLE (-325 1575);
FORCEPROP 1 LAST LOCATION R197
J 0
(-575 1475);
DISPLAY 0.702128 (-575 1475);
PAINT YELLOW (-575 1475);
FORCEPROP 1 LASTPIN (-375 1475) $PN 1
J 0
(-363 1487);
DISPLAY 0.787234 (-363 1487);
PAINT MONO (-363 1487);
FORCEPROP 1 LASTPIN (-175 1475) $PN 2
J 0
(-213 1487);
DISPLAY 0.787234 (-213 1487);
PAINT MONO (-213 1487);
FORCEPROP 0 LAST $SEC 1
J 0
(-575 1525);
DISPLAY 0.680851 (-575 1525);
PAINT MONO (-575 1525);
DISPLAY INVISIBLE (-575 1525);
FORCEPROP 0 LAST CDS_SEC 1
J 0
(-575 1525);
DISPLAY 0.680851 (-575 1525);
DISPLAY INVISIBLE (-575 1525);
FORCEADD OFFPAGE..3
R 2
(-3625 3225);
FORCEPROP 2 LAST $XR0 10 
J 0
(-3874 3225);
DISPLAY 0.638298 (-3874 3225);
PAINT MONO (-3874 3225);
FORCEPROP 2 LAST $XR1 14 
J 0
(-3964 3225);
DISPLAY 0.638298 (-3964 3225);
PAINT MONO (-3964 3225);
FORCEPROP 2 LAST CDS_LIB standard
J 0
(-3625 3225);
DISPLAY INVISIBLE (-3625 3225);
FORCEPROP 1 LAST OFFPAGE TRUE
J 2
(-3950 3100);
DISPLAY 0.872340 (-3950 3100);
PAINT GREEN (-3950 3100);
DISPLAY INVISIBLE (-3950 3100);
FORCEPROP 1 LAST COMMENT_BODY TRUE
J 2
(-3575 3125);
DISPLAY 0.872340 (-3575 3125);
PAINT PEACH (-3575 3125);
DISPLAY INVISIBLE (-3575 3125);
FORCEPROP 2 LAST PATH I2
J 0
(-3825 3275);
DISPLAY 1.021277 (-3825 3275);
DISPLAY INVISIBLE (-3825 3275);
FORCEADD UNIVERSAL_GND..1
(4850 3525);
FORCEPROP 3 LASTPIN (4850 3575) SIG_NAME GND\g
J 0
(4860 3585);
DISPLAY 0.659574 (4860 3585);
PAINT MONO (4860 3585);
DISPLAY INVISIBLE (4860 3585);
FORCEPROP 2 LAST CDS_LIB logical_power
J 0
(4850 3525);
DISPLAY INVISIBLE (4850 3525);
FORCEPROP 1 LAST PATH I208
J 0
(4925 3525);
DISPLAY 0.872340 (4925 3525);
PAINT AQUA (4925 3525);
DISPLAY INVISIBLE (4925 3525);
FORCEPROP 1 LAST HDL_POWER GND
J 1
(4875 3450);
DISPLAY 0.702128 (4875 3450);
PAINT GREEN (4875 3450);
DISPLAY INVISIBLE (4875 3450);
FORCEADD OFFPAGE..2
(1375 1900);
FORCEPROP 2 LAST $XR0 10 
J 0
(1564 1900);
DISPLAY 0.638298 (1564 1900);
PAINT MONO (1564 1900);
FORCEPROP 2 LAST $XR1 14 
J 0
(1654 1900);
DISPLAY 0.638298 (1654 1900);
PAINT MONO (1654 1900);
FORCEPROP 2 LAST PATH I21
J 0
(1725 1950);
DISPLAY 1.021277 (1725 1950);
DISPLAY INVISIBLE (1725 1950);
FORCEPROP 1 LAST COMMENT_BODY TRUE
J 0
(1330 1805);
DISPLAY 0.872340 (1330 1805);
PAINT PEACH (1330 1805);
DISPLAY INVISIBLE (1330 1805);
FORCEPROP 1 LAST OFFPAGE TRUE
J 0
(1700 1775);
DISPLAY 0.872340 (1700 1775);
PAINT GREEN (1700 1775);
DISPLAY INVISIBLE (1700 1775);
FORCEPROP 2 LAST CDS_LIB standard
J 0
(1375 1900);
DISPLAY INVISIBLE (1375 1900);
FORCEADD UNIVERSAL_POWER..1
(4850 4625);
FORCEPROP 3 LASTPIN (4850 4575) SIG_NAME P1V8_AUX\g
J 0
(4860 4585);
DISPLAY 0.659574 (4860 4585);
PAINT MONO (4860 4585);
DISPLAY INVISIBLE (4860 4585);
FORCEPROP 1 LAST HDL_POWER P1V8_AUX
J 1
(4850 4675);
DISPLAY 0.702128 (4850 4675);
PAINT GREEN (4850 4675);
FORCEPROP 2 LAST CDS_LIB logical_power
J 0
(4850 4625);
DISPLAY INVISIBLE (4850 4625);
FORCEPROP 1 LAST PATH I218
J 0
(4900 4650);
DISPLAY 0.872340 (4900 4650);
PAINT AQUA (4900 4650);
DISPLAY INVISIBLE (4900 4650);
FORCEADD UNIVERSAL_POWER..1
(-2875 2050);
FORCEPROP 3 LASTPIN (-2875 2000) SIG_NAME P3V3_AUX\g
J 0
(-2865 2010);
DISPLAY 0.659574 (-2865 2010);
PAINT MONO (-2865 2010);
DISPLAY INVISIBLE (-2865 2010);
FORCEPROP 1 LAST HDL_POWER P3V3_AUX
J 1
(-2875 2100);
DISPLAY 0.702128 (-2875 2100);
PAINT GREEN (-2875 2100);
FORCEPROP 1 LAST PATH I219
J 0
(-2825 2075);
DISPLAY 0.872340 (-2825 2075);
PAINT AQUA (-2825 2075);
DISPLAY INVISIBLE (-2825 2075);
FORCEPROP 2 LAST CDS_LIB logical_power
J 0
(-2875 2050);
DISPLAY INVISIBLE (-2875 2050);
FORCEADD OFFPAGE..2
(1375 2000);
FORCEPROP 2 LAST $XR0 14 
J 0
(1564 2000);
DISPLAY 0.638298 (1564 2000);
PAINT MONO (1564 2000);
FORCEPROP 2 LAST $XR1 10 
J 0
(1654 2000);
DISPLAY 0.638298 (1654 2000);
PAINT MONO (1654 2000);
FORCEPROP 2 LAST CDS_LIB standard
J 0
(1375 2000);
DISPLAY INVISIBLE (1375 2000);
FORCEPROP 1 LAST OFFPAGE TRUE
J 0
(1700 1875);
DISPLAY 0.872340 (1700 1875);
PAINT GREEN (1700 1875);
DISPLAY INVISIBLE (1700 1875);
FORCEPROP 1 LAST COMMENT_BODY TRUE
J 0
(1330 1905);
DISPLAY 0.872340 (1330 1905);
PAINT PEACH (1330 1905);
DISPLAY INVISIBLE (1330 1905);
FORCEPROP 2 LAST PATH I22
J 0
(1750 2050);
DISPLAY 1.021277 (1750 2050);
DISPLAY INVISIBLE (1750 2050);
FORCEADD Q_RES..2
(4625 4350);
FORCEPROP 1 LAST VALUE 4.7K
J 2
(4600 4400);
DISPLAY 0.510638 (4600 4400);
PAINT SKYBLUE (4600 4400);
FORCEPROP 1 LAST PACK_TYPE 0402LF
J 2
(4600 4200);
DISPLAY 0.510638 (4600 4200);
PAINT SKYBLUE (4600 4200);
FORCEPROP 1 LAST MATERIAL CHIP
J 2
(4600 4250);
DISPLAY 0.510638 (4600 4250);
PAINT SKYBLUE (4600 4250);
FORCEPROP 1 LAST TOLERANCE 1%
J 2
(4600 4350);
DISPLAY 0.510638 (4600 4350);
PAINT SKYBLUE (4600 4350);
FORCEPROP 1 LAST WATTAGE 1/16W
J 2
(4600 4300);
DISPLAY 0.510638 (4600 4300);
PAINT SKYBLUE (4600 4300);
FORCEPROP 2 LAST CDS_LIB pure_quanta
J 0
(4625 4350);
DISPLAY INVISIBLE (4625 4350);
FORCEPROP 1 LAST PATH I220
J 0
(4675 4525);
DISPLAY 0.978723 (4675 4525);
PAINT WHITE (4675 4525);
DISPLAY INVISIBLE (4675 4525);
FORCEPROP 1 LAST PART_NUMBER CS24702FB06
J 0
(4665 4225);
DISPLAY 0.510638 (4665 4225);
PAINT WHITE (4665 4225);
DISPLAY INVISIBLE (4665 4225);
FORCEPROP 1 LAST LOCATION R856
J 2
(4600 4450);
DISPLAY 0.702128 (4600 4450);
PAINT YELLOW (4600 4450);
FORCEPROP 1 LASTPIN (4625 4450) $PN 1
J 0
(4630 4412);
DISPLAY 0.787234 (4630 4412);
PAINT MONO (4630 4412);
FORCEPROP 1 LASTPIN (4625 4250) $PN 2
J 0
(4630 4260);
DISPLAY 0.787234 (4630 4260);
PAINT MONO (4630 4260);
FORCEPROP 0 LAST $SEC 1
J 0
(4600 4500);
DISPLAY 0.680851 (4600 4500);
PAINT MONO (4600 4500);
DISPLAY INVISIBLE (4600 4500);
FORCEPROP 0 LAST CDS_SEC 1
J 0
(4600 4500);
DISPLAY 0.680851 (4600 4500);
DISPLAY INVISIBLE (4600 4500);
FORCEADD Q_RES..2
(4400 4350);
FORCEPROP 1 LAST VALUE 4.7K
J 2
(4375 4400);
DISPLAY 0.510638 (4375 4400);
PAINT SKYBLUE (4375 4400);
FORCEPROP 1 LAST TOLERANCE 1%
J 2
(4375 4350);
DISPLAY 0.510638 (4375 4350);
PAINT SKYBLUE (4375 4350);
FORCEPROP 1 LAST PACK_TYPE 0402LF
J 2
(4375 4200);
DISPLAY 0.510638 (4375 4200);
PAINT SKYBLUE (4375 4200);
FORCEPROP 1 LAST WATTAGE 1/16W
J 2
(4375 4300);
DISPLAY 0.510638 (4375 4300);
PAINT SKYBLUE (4375 4300);
FORCEPROP 1 LAST MATERIAL EMPTY
J 2
(4375 4250);
DISPLAY 0.510638 (4375 4250);
PAINT RED (4375 4250);
FORCEPROP 1 LAST PART_NUMBER CS24702FB06
J 0
(4440 4225);
DISPLAY 0.510638 (4440 4225);
PAINT WHITE (4440 4225);
DISPLAY INVISIBLE (4440 4225);
FORCEPROP 1 LAST PATH I221
J 0
(4450 4525);
DISPLAY 0.978723 (4450 4525);
PAINT WHITE (4450 4525);
DISPLAY INVISIBLE (4450 4525);
FORCEPROP 2 LAST CDS_LIB pure_quanta
J 0
(4400 4350);
DISPLAY INVISIBLE (4400 4350);
FORCEPROP 1 LAST LOCATION R854
J 2
(4375 4450);
DISPLAY 0.702128 (4375 4450);
PAINT YELLOW (4375 4450);
FORCEPROP 1 LASTPIN (4400 4450) $PN 1
J 0
(4405 4412);
DISPLAY 0.787234 (4405 4412);
PAINT MONO (4405 4412);
FORCEPROP 1 LASTPIN (4400 4250) $PN 2
J 0
(4405 4260);
DISPLAY 0.787234 (4405 4260);
PAINT MONO (4405 4260);
FORCEPROP 0 LAST $SEC 1
J 0
(4375 4500);
DISPLAY 0.680851 (4375 4500);
PAINT MONO (4375 4500);
DISPLAY INVISIBLE (4375 4500);
FORCEPROP 0 LAST CDS_SEC 1
J 0
(4375 4500);
DISPLAY 0.680851 (4375 4500);
DISPLAY INVISIBLE (4375 4500);
FORCEADD Q_RES..2
(4850 4350);
FORCEPROP 1 LAST WATTAGE 1/16W
J 2
(4825 4300);
DISPLAY 0.510638 (4825 4300);
PAINT SKYBLUE (4825 4300);
FORCEPROP 1 LAST TOLERANCE 1%
J 2
(4825 4350);
DISPLAY 0.510638 (4825 4350);
PAINT SKYBLUE (4825 4350);
FORCEPROP 1 LAST PACK_TYPE 0402LF
J 2
(4825 4200);
DISPLAY 0.510638 (4825 4200);
PAINT SKYBLUE (4825 4200);
FORCEPROP 1 LAST MATERIAL CHIP
J 2
(4825 4250);
DISPLAY 0.510638 (4825 4250);
PAINT SKYBLUE (4825 4250);
FORCEPROP 1 LAST VALUE 4.7K
J 2
(4825 4400);
DISPLAY 0.510638 (4825 4400);
PAINT SKYBLUE (4825 4400);
FORCEPROP 2 LAST CDS_LIB pure_quanta
J 0
(4850 4350);
DISPLAY INVISIBLE (4850 4350);
FORCEPROP 1 LAST PATH I222
J 0
(4900 4525);
DISPLAY 0.978723 (4900 4525);
PAINT WHITE (4900 4525);
DISPLAY INVISIBLE (4900 4525);
FORCEPROP 1 LAST PART_NUMBER CS24702FB06
J 0
(4890 4225);
DISPLAY 0.510638 (4890 4225);
PAINT WHITE (4890 4225);
DISPLAY INVISIBLE (4890 4225);
FORCEPROP 1 LAST LOCATION R858
J 2
(4825 4450);
DISPLAY 0.702128 (4825 4450);
PAINT YELLOW (4825 4450);
FORCEPROP 1 LASTPIN (4850 4450) $PN 1
J 0
(4855 4412);
DISPLAY 0.787234 (4855 4412);
PAINT MONO (4855 4412);
FORCEPROP 1 LASTPIN (4850 4250) $PN 2
J 0
(4855 4260);
DISPLAY 0.787234 (4855 4260);
PAINT MONO (4855 4260);
FORCEPROP 0 LAST $SEC 1
J 0
(4825 4500);
DISPLAY 0.680851 (4825 4500);
PAINT MONO (4825 4500);
DISPLAY INVISIBLE (4825 4500);
FORCEPROP 0 LAST CDS_SEC 1
J 0
(4825 4500);
DISPLAY 0.680851 (4825 4500);
DISPLAY INVISIBLE (4825 4500);
FORCEADD Q_RES..2
(4400 3800);
FORCEPROP 1 LAST PART_NUMBER CS21002FB06
R 3
J 0
(4325 3950);
DISPLAY 0.510638 (4325 3950);
PAINT WHITE (4325 3950);
FORCEPROP 1 LAST VALUE 1K
J 0
(4445 3875);
DISPLAY 0.510638 (4445 3875);
PAINT SKYBLUE (4445 3875);
FORCEPROP 1 LAST PACK_TYPE 0402LF
J 0
(4450 3725);
DISPLAY 0.510638 (4450 3725);
PAINT SKYBLUE (4450 3725);
FORCEPROP 1 LAST WATTAGE 1/16W
J 0
(4440 3775);
DISPLAY 0.510638 (4440 3775);
PAINT SKYBLUE (4440 3775);
FORCEPROP 1 LAST MATERIAL CHIP
J 0
(4425 3675);
DISPLAY 0.510638 (4425 3675);
PAINT SKYBLUE (4425 3675);
FORCEPROP 1 LAST TOLERANCE 1%
J 0
(4445 3825);
DISPLAY 0.510638 (4445 3825);
PAINT SKYBLUE (4445 3825);
FORCEPROP 1 LAST PATH I223
J 0
(4450 3975);
DISPLAY 0.978723 (4450 3975);
PAINT WHITE (4450 3975);
DISPLAY INVISIBLE (4450 3975);
FORCEPROP 2 LAST CDS_LIB pure_quanta
J 0
(4400 3800);
DISPLAY INVISIBLE (4400 3800);
FORCEPROP 1 LAST LOCATION R855
J 0
(4445 3925);
DISPLAY 0.702128 (4445 3925);
PAINT YELLOW (4445 3925);
FORCEPROP 1 LASTPIN (4400 3900) $PN 1
J 0
(4405 3862);
DISPLAY 0.787234 (4405 3862);
PAINT MONO (4405 3862);
FORCEPROP 1 LASTPIN (4400 3700) $PN 2
J 0
(4405 3710);
DISPLAY 0.787234 (4405 3710);
PAINT MONO (4405 3710);
FORCEPROP 0 LAST $SEC 1
J 0
(4450 3975);
DISPLAY 0.680851 (4450 3975);
PAINT MONO (4450 3975);
DISPLAY INVISIBLE (4450 3975);
FORCEPROP 0 LAST CDS_SEC 1
J 0
(4450 3975);
DISPLAY 0.680851 (4450 3975);
DISPLAY INVISIBLE (4450 3975);
FORCEADD Q_RES..2
(4625 3800);
FORCEPROP 1 LAST VALUE 1K
J 0
(4670 3875);
DISPLAY 0.510638 (4670 3875);
PAINT SKYBLUE (4670 3875);
FORCEPROP 1 LAST TOLERANCE 1%
J 0
(4670 3825);
DISPLAY 0.510638 (4670 3825);
PAINT SKYBLUE (4670 3825);
FORCEPROP 1 LAST PACK_TYPE 0402LF
J 0
(4675 3725);
DISPLAY 0.510638 (4675 3725);
PAINT SKYBLUE (4675 3725);
FORCEPROP 1 LAST WATTAGE 1/16W
J 0
(4665 3775);
DISPLAY 0.510638 (4665 3775);
PAINT SKYBLUE (4665 3775);
FORCEPROP 1 LAST MATERIAL EMPTY
J 0
(4650 3675);
DISPLAY 0.510638 (4650 3675);
PAINT RED (4650 3675);
FORCEPROP 1 LAST PATH I224
J 0
(4675 3975);
DISPLAY 0.978723 (4675 3975);
PAINT WHITE (4675 3975);
DISPLAY INVISIBLE (4675 3975);
FORCEPROP 2 LAST CDS_LIB pure_quanta
J 0
(4625 3800);
DISPLAY INVISIBLE (4625 3800);
FORCEPROP 1 LAST PART_NUMBER CS21002FB06
R 3
J 0
(4550 3950);
DISPLAY 0.510638 (4550 3950);
PAINT WHITE (4550 3950);
DISPLAY INVISIBLE (4550 3950);
FORCEPROP 1 LAST LOCATION R857
J 0
(4670 3925);
DISPLAY 0.702128 (4670 3925);
PAINT YELLOW (4670 3925);
FORCEPROP 1 LASTPIN (4625 3900) $PN 1
J 0
(4630 3862);
DISPLAY 0.787234 (4630 3862);
PAINT MONO (4630 3862);
FORCEPROP 1 LASTPIN (4625 3700) $PN 2
J 0
(4630 3710);
DISPLAY 0.787234 (4630 3710);
PAINT MONO (4630 3710);
FORCEPROP 0 LAST $SEC 1
J 0
(4675 3975);
DISPLAY 0.680851 (4675 3975);
PAINT MONO (4675 3975);
DISPLAY INVISIBLE (4675 3975);
FORCEPROP 0 LAST CDS_SEC 1
J 0
(4675 3975);
DISPLAY 0.680851 (4675 3975);
DISPLAY INVISIBLE (4675 3975);
FORCEADD Q_RES..2
(4850 3800);
FORCEPROP 1 LAST MATERIAL EMPTY
J 0
(4875 3675);
DISPLAY 0.510638 (4875 3675);
PAINT RED (4875 3675);
FORCEPROP 1 LAST PACK_TYPE 0402LF
J 0
(4900 3725);
DISPLAY 0.510638 (4900 3725);
PAINT SKYBLUE (4900 3725);
FORCEPROP 1 LAST WATTAGE 1/16W
J 0
(4890 3775);
DISPLAY 0.510638 (4890 3775);
PAINT SKYBLUE (4890 3775);
FORCEPROP 1 LAST TOLERANCE 1%
J 0
(4895 3825);
DISPLAY 0.510638 (4895 3825);
PAINT SKYBLUE (4895 3825);
FORCEPROP 1 LAST VALUE 1K
J 0
(4895 3875);
DISPLAY 0.510638 (4895 3875);
PAINT SKYBLUE (4895 3875);
FORCEPROP 1 LAST PART_NUMBER CS21002FB06
R 3
J 0
(4775 3950);
DISPLAY 0.510638 (4775 3950);
PAINT WHITE (4775 3950);
DISPLAY INVISIBLE (4775 3950);
FORCEPROP 2 LAST CDS_LIB pure_quanta
J 0
(4850 3800);
DISPLAY INVISIBLE (4850 3800);
FORCEPROP 1 LAST PATH I225
J 0
(4900 3975);
DISPLAY 0.978723 (4900 3975);
PAINT WHITE (4900 3975);
DISPLAY INVISIBLE (4900 3975);
FORCEPROP 1 LAST LOCATION R865
J 0
(4895 3925);
DISPLAY 0.702128 (4895 3925);
PAINT YELLOW (4895 3925);
FORCEPROP 1 LASTPIN (4850 3900) $PN 1
J 0
(4855 3862);
DISPLAY 0.787234 (4855 3862);
PAINT MONO (4855 3862);
FORCEPROP 1 LASTPIN (4850 3700) $PN 2
J 0
(4855 3710);
DISPLAY 0.787234 (4855 3710);
PAINT MONO (4855 3710);
FORCEPROP 0 LAST $SEC 1
J 0
(4900 3975);
DISPLAY 0.680851 (4900 3975);
PAINT MONO (4900 3975);
DISPLAY INVISIBLE (4900 3975);
FORCEPROP 0 LAST CDS_SEC 1
J 0
(4900 3975);
DISPLAY 0.680851 (4900 3975);
DISPLAY INVISIBLE (4900 3975);
FORCEADD OFFPAGE..4
(3775 4675);
FORCEPROP 2 LAST CDS_LIB standard
J 0
(3775 4675);
DISPLAY INVISIBLE (3775 4675);
FORCEPROP 1 LAST OFFPAGE TRUE
J 0
(4100 4550);
DISPLAY 0.872340 (4100 4550);
PAINT GREEN (4100 4550);
DISPLAY INVISIBLE (4100 4550);
FORCEPROP 1 LAST COMMENT_BODY TRUE
J 0
(3750 4575);
DISPLAY 0.872340 (3750 4575);
PAINT PEACH (3750 4575);
DISPLAY INVISIBLE (3750 4575);
FORCEPROP 2 LAST PATH I228
J 0
(3950 4750);
DISPLAY 0.680851 (3950 4750);
DISPLAY INVISIBLE (3950 4750);
FORCEADD Q_RES..1
(2800 4675);
FORCEPROP 1 LAST VALUE 33.2
J 0
(2900 4675);
DISPLAY 0.510638 (2900 4675);
PAINT SKYBLUE (2900 4675);
FORCEPROP 1 LAST MATERIAL CHIP
J 0
(3000 4675);
DISPLAY 0.510638 (3000 4675);
PAINT SKYBLUE (3000 4675);
FORCEPROP 1 LAST TOLERANCE 1%
J 0
(2925 4675);
DISPLAY 0.510638 (2925 4675);
PAINT SKYBLUE (2925 4675);
DISPLAY INVISIBLE (2925 4675);
FORCEPROP 1 LAST PART_NUMBER CS03322FB03
J 0
(2750 4775);
DISPLAY 0.510638 (2750 4775);
PAINT WHITE (2750 4775);
DISPLAY INVISIBLE (2750 4775);
FORCEPROP 1 LAST PACK_TYPE 0402LF
J 0
(3050 4525);
DISPLAY 0.510638 (3050 4525);
PAINT SKYBLUE (3050 4525);
DISPLAY INVISIBLE (3050 4525);
FORCEPROP 1 LAST WATTAGE 1/16W
J 2
(2775 4525);
DISPLAY 0.510638 (2775 4525);
PAINT SKYBLUE (2775 4525);
DISPLAY INVISIBLE (2775 4525);
FORCEPROP 1 LAST PATH I229
J 0
(2750 4825);
DISPLAY 0.978723 (2750 4825);
PAINT WHITE (2750 4825);
DISPLAY INVISIBLE (2750 4825);
FORCEPROP 2 LAST CDS_LIB pure_quanta
J 0
(2800 4675);
DISPLAY INVISIBLE (2800 4675);
FORCEPROP 1 LAST $LOCATION R884
J 0
(2600 4675);
DISPLAY 0.702128 (2600 4675);
PAINT YELLOW (2600 4675);
FORCEPROP 1 LASTPIN (2700 4675) $PN 1
J 0
(2712 4687);
DISPLAY 0.787234 (2712 4687);
PAINT MONO (2712 4687);
FORCEPROP 1 LASTPIN (2900 4675) $PN 2
J 0
(2862 4687);
DISPLAY 0.787234 (2862 4687);
PAINT MONO (2862 4687);
FORCEPROP 0 LAST CDS_LOCATION R884
J 0
(2600 4725);
DISPLAY 0.680851 (2600 4725);
DISPLAY INVISIBLE (2600 4725);
FORCEPROP 0 LAST $SEC 1
J 0
(2600 4725);
DISPLAY 0.680851 (2600 4725);
PAINT MONO (2600 4725);
DISPLAY INVISIBLE (2600 4725);
FORCEPROP 0 LAST CDS_SEC 1
J 0
(2600 4725);
DISPLAY 0.680851 (2600 4725);
DISPLAY INVISIBLE (2600 4725);
FORCEADD UNIVERSAL_POWER..1
(3100 5050);
FORCEPROP 3 LASTPIN (3100 5000) SIG_NAME P1V8_AUX\g
J 0
(3110 5010);
DISPLAY 0.659574 (3110 5010);
PAINT MONO (3110 5010);
DISPLAY INVISIBLE (3110 5010);
FORCEPROP 1 LAST HDL_POWER P1V8_AUX
J 1
(3100 5100);
DISPLAY 0.702128 (3100 5100);
PAINT GREEN (3100 5100);
FORCEPROP 1 LAST PATH I230
J 0
(3150 5075);
DISPLAY 0.872340 (3150 5075);
PAINT AQUA (3150 5075);
DISPLAY INVISIBLE (3150 5075);
FORCEPROP 2 LAST CDS_LIB logical_power
J 0
(3100 5050);
DISPLAY INVISIBLE (3100 5050);
FORCEADD Q_RES..2
(3100 4875);
FORCEPROP 1 LAST TOLERANCE 1%
J 2
(3075 4875);
DISPLAY 0.510638 (3075 4875);
PAINT SKYBLUE (3075 4875);
FORCEPROP 1 LAST VALUE 4.7K
J 2
(3075 4925);
DISPLAY 0.510638 (3075 4925);
PAINT SKYBLUE (3075 4925);
FORCEPROP 1 LAST MATERIAL CHIP
J 2
(3075 4775);
DISPLAY 0.510638 (3075 4775);
PAINT SKYBLUE (3075 4775);
FORCEPROP 1 LAST WATTAGE 1/16W
J 2
(3075 4825);
DISPLAY 0.510638 (3075 4825);
PAINT SKYBLUE (3075 4825);
FORCEPROP 1 LAST PACK_TYPE 0402LF
J 2
(3075 4725);
DISPLAY 0.510638 (3075 4725);
PAINT SKYBLUE (3075 4725);
FORCEPROP 2 LAST CDS_LIB pure_quanta
J 0
(3100 4875);
DISPLAY INVISIBLE (3100 4875);
FORCEPROP 1 LAST PATH I231
J 0
(3150 5050);
DISPLAY 0.978723 (3150 5050);
PAINT WHITE (3150 5050);
DISPLAY INVISIBLE (3150 5050);
FORCEPROP 1 LAST PART_NUMBER CS24702FB06
J 0
(3140 4750);
DISPLAY 0.510638 (3140 4750);
PAINT WHITE (3140 4750);
DISPLAY INVISIBLE (3140 4750);
FORCEPROP 1 LAST $LOCATION R885
J 2
(3075 4975);
DISPLAY 0.702128 (3075 4975);
PAINT YELLOW (3075 4975);
FORCEPROP 1 LASTPIN (3100 4975) $PN 1
J 0
(3105 4937);
DISPLAY 0.787234 (3105 4937);
PAINT MONO (3105 4937);
FORCEPROP 1 LASTPIN (3100 4775) $PN 2
J 0
(3105 4785);
DISPLAY 0.787234 (3105 4785);
PAINT MONO (3105 4785);
FORCEPROP 0 LAST CDS_LOCATION R885
J 0
(3075 5025);
DISPLAY 0.680851 (3075 5025);
DISPLAY INVISIBLE (3075 5025);
FORCEPROP 0 LAST $SEC 1
J 0
(3075 5025);
DISPLAY 0.680851 (3075 5025);
PAINT MONO (3075 5025);
DISPLAY INVISIBLE (3075 5025);
FORCEPROP 0 LAST CDS_SEC 1
J 0
(3075 5025);
DISPLAY 0.680851 (3075 5025);
DISPLAY INVISIBLE (3075 5025);
FORCEADD Q_RES..1
(-2150 3425);
FORCEPROP 1 LAST MATERIAL CHIP
J 0
(-1950 3425);
DISPLAY 0.510638 (-1950 3425);
PAINT SKYBLUE (-1950 3425);
FORCEPROP 1 LAST VALUE 110
J 0
(-2050 3425);
DISPLAY 0.510638 (-2050 3425);
PAINT SKYBLUE (-2050 3425);
FORCEPROP 1 LAST PART_NUMBER CS11102FB03
J 0
(-2275 3475);
DISPLAY 0.510638 (-2275 3475);
PAINT WHITE (-2275 3475);
FORCEPROP 2 LAST CDS_LIB pure_quanta
J 0
(-2150 3425);
DISPLAY INVISIBLE (-2150 3425);
FORCEPROP 1 LAST PATH I232
J 0
(-2200 3575);
DISPLAY 0.978723 (-2200 3575);
PAINT WHITE (-2200 3575);
DISPLAY INVISIBLE (-2200 3575);
FORCEPROP 1 LAST WATTAGE 1/16W
J 2
(-2500 3325);
DISPLAY 0.510638 (-2500 3325);
PAINT SKYBLUE (-2500 3325);
DISPLAY INVISIBLE (-2500 3325);
FORCEPROP 1 LAST TOLERANCE 1%
J 0
(-2125 3325);
DISPLAY 0.510638 (-2125 3325);
PAINT SKYBLUE (-2125 3325);
DISPLAY INVISIBLE (-2125 3325);
FORCEPROP 1 LAST PACK_TYPE 0402LF
J 0
(-2325 3325);
DISPLAY 0.510638 (-2325 3325);
PAINT SKYBLUE (-2325 3325);
DISPLAY INVISIBLE (-2325 3325);
FORCEPROP 1 LAST LOCATION R184
J 0
(-2350 3425);
DISPLAY 0.702128 (-2350 3425);
PAINT YELLOW (-2350 3425);
FORCEPROP 1 LASTPIN (-2250 3425) $PN 1
J 0
(-2238 3437);
DISPLAY 0.787234 (-2238 3437);
PAINT MONO (-2238 3437);
FORCEPROP 1 LASTPIN (-2050 3425) $PN 2
J 0
(-2088 3437);
DISPLAY 0.787234 (-2088 3437);
PAINT MONO (-2088 3437);
FORCEPROP 0 LAST $SEC 1
J 0
(-2275 3500);
DISPLAY 0.680851 (-2275 3500);
PAINT MONO (-2275 3500);
DISPLAY INVISIBLE (-2275 3500);
FORCEPROP 0 LAST CDS_SEC 1
J 0
(-2275 3500);
DISPLAY 0.680851 (-2275 3500);
DISPLAY INVISIBLE (-2275 3500);
FORCEADD Q_RES..1
(-2150 3275);
FORCEPROP 1 LAST MATERIAL CHIP
J 0
(-1950 3275);
DISPLAY 0.510638 (-1950 3275);
PAINT SKYBLUE (-1950 3275);
FORCEPROP 1 LAST VALUE 110
J 0
(-2050 3275);
DISPLAY 0.510638 (-2050 3275);
PAINT SKYBLUE (-2050 3275);
FORCEPROP 1 LAST PART_NUMBER CS11102FB03
J 0
(-2275 3325);
DISPLAY 0.510638 (-2275 3325);
PAINT WHITE (-2275 3325);
FORCEPROP 1 LAST PACK_TYPE 0402LF
J 0
(-2325 3175);
DISPLAY 0.510638 (-2325 3175);
PAINT SKYBLUE (-2325 3175);
DISPLAY INVISIBLE (-2325 3175);
FORCEPROP 1 LAST TOLERANCE 1%
J 0
(-2125 3175);
DISPLAY 0.510638 (-2125 3175);
PAINT SKYBLUE (-2125 3175);
DISPLAY INVISIBLE (-2125 3175);
FORCEPROP 1 LAST WATTAGE 1/16W
J 2
(-2500 3175);
DISPLAY 0.510638 (-2500 3175);
PAINT SKYBLUE (-2500 3175);
DISPLAY INVISIBLE (-2500 3175);
FORCEPROP 1 LAST PATH I233
J 0
(-2200 3425);
DISPLAY 0.978723 (-2200 3425);
PAINT WHITE (-2200 3425);
DISPLAY INVISIBLE (-2200 3425);
FORCEPROP 2 LAST CDS_LIB pure_quanta
J 0
(-2150 3275);
DISPLAY INVISIBLE (-2150 3275);
FORCEPROP 1 LAST LOCATION R186
J 0
(-2350 3275);
DISPLAY 0.702128 (-2350 3275);
PAINT YELLOW (-2350 3275);
FORCEPROP 1 LASTPIN (-2250 3275) $PN 1
J 0
(-2238 3287);
DISPLAY 0.787234 (-2238 3287);
PAINT MONO (-2238 3287);
FORCEPROP 1 LASTPIN (-2050 3275) $PN 2
J 0
(-2088 3287);
DISPLAY 0.787234 (-2088 3287);
PAINT MONO (-2088 3287);
FORCEPROP 0 LAST $SEC 1
J 0
(-2275 3350);
DISPLAY 0.680851 (-2275 3350);
PAINT MONO (-2275 3350);
DISPLAY INVISIBLE (-2275 3350);
FORCEPROP 0 LAST CDS_SEC 1
J 0
(-2275 3350);
DISPLAY 0.680851 (-2275 3350);
DISPLAY INVISIBLE (-2275 3350);
FORCEADD Q_RES..1
(3100 3425);
FORCEPROP 1 LAST PART_NUMBER CS11102FB03
J 0
(2975 3475);
DISPLAY 0.510638 (2975 3475);
PAINT WHITE (2975 3475);
FORCEPROP 1 LAST VALUE 110
J 0
(3200 3425);
DISPLAY 0.510638 (3200 3425);
PAINT SKYBLUE (3200 3425);
FORCEPROP 1 LAST MATERIAL CHIP
J 0
(3300 3425);
DISPLAY 0.510638 (3300 3425);
PAINT SKYBLUE (3300 3425);
FORCEPROP 1 LAST PACK_TYPE 0402LF
J 0
(2925 3325);
DISPLAY 0.510638 (2925 3325);
PAINT SKYBLUE (2925 3325);
DISPLAY INVISIBLE (2925 3325);
FORCEPROP 1 LAST TOLERANCE 1%
J 0
(3125 3325);
DISPLAY 0.510638 (3125 3325);
PAINT SKYBLUE (3125 3325);
DISPLAY INVISIBLE (3125 3325);
FORCEPROP 1 LAST WATTAGE 1/16W
J 2
(2750 3325);
DISPLAY 0.510638 (2750 3325);
PAINT SKYBLUE (2750 3325);
DISPLAY INVISIBLE (2750 3325);
FORCEPROP 1 LAST PATH I234
J 0
(3050 3575);
DISPLAY 0.978723 (3050 3575);
PAINT WHITE (3050 3575);
DISPLAY INVISIBLE (3050 3575);
FORCEPROP 2 LAST CDS_LIB pure_quanta
J 0
(3100 3425);
DISPLAY INVISIBLE (3100 3425);
FORCEPROP 1 LAST LOCATION R198
J 0
(2900 3425);
DISPLAY 0.702128 (2900 3425);
PAINT YELLOW (2900 3425);
FORCEPROP 1 LASTPIN (3000 3425) $PN 1
J 0
(3012 3437);
DISPLAY 0.787234 (3012 3437);
PAINT MONO (3012 3437);
FORCEPROP 1 LASTPIN (3200 3425) $PN 2
J 0
(3162 3437);
DISPLAY 0.787234 (3162 3437);
PAINT MONO (3162 3437);
FORCEPROP 0 LAST $SEC 1
J 0
(2975 3500);
DISPLAY 0.680851 (2975 3500);
PAINT MONO (2975 3500);
DISPLAY INVISIBLE (2975 3500);
FORCEPROP 0 LAST CDS_SEC 1
J 0
(2975 3500);
DISPLAY 0.680851 (2975 3500);
DISPLAY INVISIBLE (2975 3500);
FORCEADD Q_RES..1
(3100 3275);
FORCEPROP 1 LAST VALUE 110
J 0
(3200 3275);
DISPLAY 0.510638 (3200 3275);
PAINT SKYBLUE (3200 3275);
FORCEPROP 1 LAST MATERIAL CHIP
J 0
(3300 3275);
DISPLAY 0.510638 (3300 3275);
PAINT SKYBLUE (3300 3275);
FORCEPROP 1 LAST PART_NUMBER CS11102FB03
J 0
(2975 3325);
DISPLAY 0.510638 (2975 3325);
PAINT WHITE (2975 3325);
FORCEPROP 1 LAST WATTAGE 1/16W
J 2
(2750 3175);
DISPLAY 0.510638 (2750 3175);
PAINT SKYBLUE (2750 3175);
DISPLAY INVISIBLE (2750 3175);
FORCEPROP 1 LAST TOLERANCE 1%
J 0
(3125 3175);
DISPLAY 0.510638 (3125 3175);
PAINT SKYBLUE (3125 3175);
DISPLAY INVISIBLE (3125 3175);
FORCEPROP 1 LAST PACK_TYPE 0402LF
J 0
(2925 3175);
DISPLAY 0.510638 (2925 3175);
PAINT SKYBLUE (2925 3175);
DISPLAY INVISIBLE (2925 3175);
FORCEPROP 1 LAST PATH I235
J 0
(3050 3425);
DISPLAY 0.978723 (3050 3425);
PAINT WHITE (3050 3425);
DISPLAY INVISIBLE (3050 3425);
FORCEPROP 2 LAST CDS_LIB pure_quanta
J 0
(3100 3275);
DISPLAY INVISIBLE (3100 3275);
FORCEPROP 1 LAST LOCATION R200
J 0
(2900 3275);
DISPLAY 0.702128 (2900 3275);
PAINT YELLOW (2900 3275);
FORCEPROP 1 LASTPIN (3000 3275) $PN 1
J 0
(3012 3287);
DISPLAY 0.787234 (3012 3287);
PAINT MONO (3012 3287);
FORCEPROP 1 LASTPIN (3200 3275) $PN 2
J 0
(3162 3287);
DISPLAY 0.787234 (3162 3287);
PAINT MONO (3162 3287);
FORCEPROP 0 LAST $SEC 1
J 0
(2975 3350);
DISPLAY 0.680851 (2975 3350);
PAINT MONO (2975 3350);
DISPLAY INVISIBLE (2975 3350);
FORCEPROP 0 LAST CDS_SEC 1
J 0
(2975 3350);
DISPLAY 0.680851 (2975 3350);
DISPLAY INVISIBLE (2975 3350);
FORCEADD Q_RES..1
(-2150 3375);
FORCEPROP 1 LAST PACK_TYPE 0402LF
J 0
(-1825 3375);
DISPLAY 0.510638 (-1825 3375);
FORCEPROP 1 LAST MATERIAL CHIP
J 0
(-1950 3375);
DISPLAY 0.510638 (-1950 3375);
FORCEPROP 1 LAST VALUE 33.2
J 2
(-1975 3375);
DISPLAY 0.510638 (-1975 3375);
FORCEPROP 1 LAST WATTAGE 1/16W
J 2
(-2175 3225);
DISPLAY 0.510638 (-2175 3225);
DISPLAY INVISIBLE (-2175 3225);
FORCEPROP 1 LAST PATH I236
J 0
(-2200 3525);
DISPLAY 0.978723 (-2200 3525);
PAINT WHITE (-2200 3525);
DISPLAY INVISIBLE (-2200 3525);
FORCEPROP 2 LAST CDS_LIB pure_quanta
J 0
(-2150 3375);
DISPLAY INVISIBLE (-2150 3375);
FORCEPROP 1 LAST TOLERANCE 1%
J 0
(-2150 3275);
DISPLAY 0.510638 (-2150 3275);
DISPLAY INVISIBLE (-2150 3275);
FORCEPROP 1 LAST PART_NUMBER CS03322FB03
J 0
(-2475 3375);
DISPLAY 0.510638 (-2475 3375);
DISPLAY INVISIBLE (-2475 3375);
FORCEPROP 1 LAST LOCATION R185
J 0
(-2350 3375);
DISPLAY 0.808511 (-2350 3375);
PAINT YELLOW (-2350 3375);
FORCEPROP 1 LASTPIN (-2250 3375) $PN 1
J 0
(-2238 3387);
DISPLAY 0.787234 (-2238 3387);
PAINT MONO (-2238 3387);
FORCEPROP 1 LASTPIN (-2050 3375) $PN 2
J 0
(-2088 3387);
DISPLAY 0.787234 (-2088 3387);
PAINT MONO (-2088 3387);
FORCEPROP 0 LAST $SEC 1
J 0
(-2350 3425);
DISPLAY 0.680851 (-2350 3425);
PAINT MONO (-2350 3425);
DISPLAY INVISIBLE (-2350 3425);
FORCEPROP 0 LAST CDS_SEC 1
J 0
(-2350 3425);
DISPLAY 0.680851 (-2350 3425);
DISPLAY INVISIBLE (-2350 3425);
FORCEADD Q_RES..1
(-2150 3225);
FORCEPROP 1 LAST MATERIAL CHIP
J 0
(-1950 3225);
DISPLAY 0.510638 (-1950 3225);
FORCEPROP 1 LAST VALUE 33.2
J 2
(-1975 3225);
DISPLAY 0.510638 (-1975 3225);
FORCEPROP 1 LAST PACK_TYPE 0402LF
J 0
(-1825 3225);
DISPLAY 0.510638 (-1825 3225);
FORCEPROP 2 LAST CDS_LIB pure_quanta
J 0
(-2150 3225);
DISPLAY INVISIBLE (-2150 3225);
FORCEPROP 1 LAST PATH I237
J 0
(-2200 3375);
DISPLAY 0.978723 (-2200 3375);
PAINT WHITE (-2200 3375);
DISPLAY INVISIBLE (-2200 3375);
FORCEPROP 1 LAST WATTAGE 1/16W
J 2
(-2175 3075);
DISPLAY 0.510638 (-2175 3075);
DISPLAY INVISIBLE (-2175 3075);
FORCEPROP 1 LAST TOLERANCE 1%
J 0
(-2150 3125);
DISPLAY 0.510638 (-2150 3125);
DISPLAY INVISIBLE (-2150 3125);
FORCEPROP 1 LAST PART_NUMBER CS03322FB03
J 0
(-2475 3225);
DISPLAY 0.510638 (-2475 3225);
DISPLAY INVISIBLE (-2475 3225);
FORCEPROP 1 LAST LOCATION R187
J 0
(-2350 3225);
DISPLAY 0.808511 (-2350 3225);
PAINT YELLOW (-2350 3225);
FORCEPROP 1 LASTPIN (-2250 3225) $PN 1
J 0
(-2238 3237);
DISPLAY 0.787234 (-2238 3237);
PAINT MONO (-2238 3237);
FORCEPROP 1 LASTPIN (-2050 3225) $PN 2
J 0
(-2088 3237);
DISPLAY 0.787234 (-2088 3237);
PAINT MONO (-2088 3237);
FORCEPROP 0 LAST $SEC 1
J 0
(-2350 3275);
DISPLAY 0.680851 (-2350 3275);
PAINT MONO (-2350 3275);
DISPLAY INVISIBLE (-2350 3275);
FORCEPROP 0 LAST CDS_SEC 1
J 0
(-2350 3275);
DISPLAY 0.680851 (-2350 3275);
DISPLAY INVISIBLE (-2350 3275);
FORCEADD Q_RES..1
(3100 3375);
FORCEPROP 1 LAST VALUE 33.2
J 2
(3275 3375);
DISPLAY 0.510638 (3275 3375);
FORCEPROP 1 LAST MATERIAL CHIP
J 0
(3300 3375);
DISPLAY 0.510638 (3300 3375);
FORCEPROP 2 LAST CDS_LIB pure_quanta
J 0
(3100 3375);
DISPLAY INVISIBLE (3100 3375);
FORCEPROP 1 LAST PATH I238
J 0
(3050 3525);
DISPLAY 0.978723 (3050 3525);
PAINT WHITE (3050 3525);
DISPLAY INVISIBLE (3050 3525);
FORCEPROP 1 LAST WATTAGE 1/16W
J 2
(3075 3225);
DISPLAY 0.510638 (3075 3225);
DISPLAY INVISIBLE (3075 3225);
FORCEPROP 1 LAST TOLERANCE 1%
J 0
(3100 3275);
DISPLAY 0.510638 (3100 3275);
DISPLAY INVISIBLE (3100 3275);
FORCEPROP 1 LAST PART_NUMBER CS03322FB03
J 0
(2775 3375);
DISPLAY 0.510638 (2775 3375);
DISPLAY INVISIBLE (2775 3375);
FORCEPROP 1 LAST PACK_TYPE 0402LF
J 0
(3400 3375);
DISPLAY 0.510638 (3400 3375);
DISPLAY INVISIBLE (3400 3375);
FORCEPROP 1 LAST LOCATION R199
J 0
(2900 3375);
DISPLAY 0.808511 (2900 3375);
PAINT YELLOW (2900 3375);
FORCEPROP 1 LASTPIN (3000 3375) $PN 1
J 0
(3012 3387);
DISPLAY 0.787234 (3012 3387);
PAINT MONO (3012 3387);
FORCEPROP 1 LASTPIN (3200 3375) $PN 2
J 0
(3162 3387);
DISPLAY 0.787234 (3162 3387);
PAINT MONO (3162 3387);
FORCEPROP 0 LAST $SEC 1
J 0
(2900 3425);
DISPLAY 0.680851 (2900 3425);
PAINT MONO (2900 3425);
DISPLAY INVISIBLE (2900 3425);
FORCEPROP 0 LAST CDS_SEC 1
J 0
(2900 3425);
DISPLAY 0.680851 (2900 3425);
DISPLAY INVISIBLE (2900 3425);
FORCEADD Q_RES..1
(3100 3225);
FORCEPROP 1 LAST MATERIAL CHIP
J 0
(3300 3225);
DISPLAY 0.510638 (3300 3225);
FORCEPROP 1 LAST VALUE 33.2
J 2
(3275 3225);
DISPLAY 0.510638 (3275 3225);
FORCEPROP 2 LAST CDS_LIB pure_quanta
J 0
(3100 3225);
DISPLAY INVISIBLE (3100 3225);
FORCEPROP 1 LAST PATH I239
J 0
(3050 3375);
DISPLAY 0.978723 (3050 3375);
PAINT WHITE (3050 3375);
DISPLAY INVISIBLE (3050 3375);
FORCEPROP 1 LAST WATTAGE 1/16W
J 2
(3075 3075);
DISPLAY 0.510638 (3075 3075);
DISPLAY INVISIBLE (3075 3075);
FORCEPROP 1 LAST TOLERANCE 1%
J 0
(3100 3125);
DISPLAY 0.510638 (3100 3125);
DISPLAY INVISIBLE (3100 3125);
FORCEPROP 1 LAST PART_NUMBER CS03322FB03
J 0
(2775 3225);
DISPLAY 0.510638 (2775 3225);
DISPLAY INVISIBLE (2775 3225);
FORCEPROP 1 LAST PACK_TYPE 0402LF
J 0
(3400 3225);
DISPLAY 0.510638 (3400 3225);
DISPLAY INVISIBLE (3400 3225);
FORCEPROP 1 LAST LOCATION R201
J 0
(2900 3225);
DISPLAY 0.787234 (2900 3225);
PAINT YELLOW (2900 3225);
FORCEPROP 1 LASTPIN (3000 3225) $PN 1
J 0
(3012 3237);
DISPLAY 0.787234 (3012 3237);
PAINT MONO (3012 3237);
FORCEPROP 1 LASTPIN (3200 3225) $PN 2
J 0
(3162 3237);
DISPLAY 0.787234 (3162 3237);
PAINT MONO (3162 3237);
FORCEPROP 0 LAST $SEC 1
J 0
(2900 3275);
DISPLAY 0.680851 (2900 3275);
PAINT MONO (2900 3275);
DISPLAY INVISIBLE (2900 3275);
FORCEPROP 0 LAST CDS_SEC 1
J 0
(2900 3275);
DISPLAY 0.680851 (2900 3275);
DISPLAY INVISIBLE (2900 3275);
FORCEADD OFFPAGE..3
R 2
(-3625 3375);
FORCEPROP 2 LAST $XR0 10 
J 0
(-3874 3375);
DISPLAY 0.638298 (-3874 3375);
PAINT MONO (-3874 3375);
FORCEPROP 2 LAST $XR1 14 
J 0
(-3964 3375);
DISPLAY 0.638298 (-3964 3375);
PAINT MONO (-3964 3375);
FORCEPROP 2 LAST CDS_LIB standard
J 0
(-3625 3375);
DISPLAY INVISIBLE (-3625 3375);
FORCEPROP 1 LAST OFFPAGE TRUE
J 2
(-3950 3250);
DISPLAY 0.872340 (-3950 3250);
PAINT GREEN (-3950 3250);
DISPLAY INVISIBLE (-3950 3250);
FORCEPROP 1 LAST COMMENT_BODY TRUE
J 2
(-3575 3275);
DISPLAY 0.872340 (-3575 3275);
PAINT PEACH (-3575 3275);
DISPLAY INVISIBLE (-3575 3275);
FORCEPROP 2 LAST PATH I3
J 0
(-3825 3425);
DISPLAY 1.021277 (-3825 3425);
DISPLAY INVISIBLE (-3825 3425);
FORCEADD OFFPAGE..2
R 2
(-3625 3425);
FORCEPROP 2 LAST $XR0 14 
J 0
(-3849 3425);
DISPLAY 0.638298 (-3849 3425);
PAINT MONO (-3849 3425);
FORCEPROP 2 LAST $XR1 10 
J 0
(-3939 3425);
DISPLAY 0.638298 (-3939 3425);
PAINT MONO (-3939 3425);
FORCEPROP 2 LAST PATH I4
J 0
(-3825 3475);
DISPLAY 1.021277 (-3825 3475);
DISPLAY INVISIBLE (-3825 3475);
FORCEPROP 1 LAST COMMENT_BODY TRUE
J 2
(-3580 3330);
DISPLAY 0.872340 (-3580 3330);
PAINT PEACH (-3580 3330);
DISPLAY INVISIBLE (-3580 3330);
FORCEPROP 1 LAST OFFPAGE TRUE
J 2
(-3950 3300);
DISPLAY 0.872340 (-3950 3300);
PAINT GREEN (-3950 3300);
DISPLAY INVISIBLE (-3950 3300);
FORCEPROP 2 LAST CDS_LIB standard
J 0
(-3625 3425);
DISPLAY INVISIBLE (-3625 3425);
FORCEADD OFFPAGE..3
(4700 3225);
FORCEPROP 2 LAST $XR1 14 
J 0
(5004 3225);
DISPLAY 0.638298 (5004 3225);
PAINT MONO (5004 3225);
FORCEPROP 2 LAST $XR0 10 
J 0
(4914 3225);
DISPLAY 0.638298 (4914 3225);
PAINT MONO (4914 3225);
FORCEPROP 2 LAST CDS_LIB standard
J 0
(4700 3225);
DISPLAY INVISIBLE (4700 3225);
FORCEPROP 1 LAST OFFPAGE TRUE
J 0
(5025 3100);
DISPLAY 0.872340 (5025 3100);
PAINT GREEN (5025 3100);
DISPLAY INVISIBLE (5025 3100);
FORCEPROP 1 LAST COMMENT_BODY TRUE
J 0
(4650 3125);
DISPLAY 0.872340 (4650 3125);
PAINT PEACH (4650 3125);
DISPLAY INVISIBLE (4650 3125);
FORCEPROP 2 LAST PATH I45
J 0
(5075 3275);
DISPLAY 1.021277 (5075 3275);
DISPLAY INVISIBLE (5075 3275);
FORCEADD OFFPAGE..2
(4700 3275);
FORCEPROP 2 LAST $XR0 14 
J 0
(4889 3275);
DISPLAY 0.638298 (4889 3275);
PAINT MONO (4889 3275);
FORCEPROP 2 LAST $XR1 10 
J 0
(4979 3275);
DISPLAY 0.638298 (4979 3275);
PAINT MONO (4979 3275);
FORCEPROP 2 LAST CDS_LIB standard
J 0
(4700 3275);
DISPLAY INVISIBLE (4700 3275);
FORCEPROP 1 LAST OFFPAGE TRUE
J 0
(5025 3150);
DISPLAY 0.872340 (5025 3150);
PAINT GREEN (5025 3150);
DISPLAY INVISIBLE (5025 3150);
FORCEPROP 1 LAST COMMENT_BODY TRUE
J 0
(4655 3180);
DISPLAY 0.872340 (4655 3180);
PAINT PEACH (4655 3180);
DISPLAY INVISIBLE (4655 3180);
FORCEPROP 2 LAST PATH I46
J 0
(5075 3325);
DISPLAY 1.021277 (5075 3325);
DISPLAY INVISIBLE (5075 3325);
FORCEADD OFFPAGE..3
(4700 3375);
FORCEPROP 2 LAST $XR1 14 
J 0
(5004 3375);
DISPLAY 0.638298 (5004 3375);
PAINT MONO (5004 3375);
FORCEPROP 2 LAST $XR0 10 
J 0
(4914 3375);
DISPLAY 0.638298 (4914 3375);
PAINT MONO (4914 3375);
FORCEPROP 2 LAST CDS_LIB standard
J 0
(4700 3375);
DISPLAY INVISIBLE (4700 3375);
FORCEPROP 1 LAST OFFPAGE TRUE
J 0
(5025 3250);
DISPLAY 0.872340 (5025 3250);
PAINT GREEN (5025 3250);
DISPLAY INVISIBLE (5025 3250);
FORCEPROP 1 LAST COMMENT_BODY TRUE
J 0
(4650 3275);
DISPLAY 0.872340 (4650 3275);
PAINT PEACH (4650 3275);
DISPLAY INVISIBLE (4650 3275);
FORCEPROP 2 LAST PATH I47
J 0
(5075 3425);
DISPLAY 1.021277 (5075 3425);
DISPLAY INVISIBLE (5075 3425);
FORCEADD OFFPAGE..2
(4700 3425);
FORCEPROP 2 LAST $XR0 14 
J 0
(4889 3425);
DISPLAY 0.638298 (4889 3425);
PAINT MONO (4889 3425);
FORCEPROP 2 LAST $XR1 10 
J 0
(4979 3425);
DISPLAY 0.638298 (4979 3425);
PAINT MONO (4979 3425);
FORCEPROP 2 LAST CDS_LIB standard
J 0
(4700 3425);
DISPLAY INVISIBLE (4700 3425);
FORCEPROP 1 LAST OFFPAGE TRUE
J 0
(5025 3300);
DISPLAY 0.872340 (5025 3300);
PAINT GREEN (5025 3300);
DISPLAY INVISIBLE (5025 3300);
FORCEPROP 1 LAST COMMENT_BODY TRUE
J 0
(4655 3330);
DISPLAY 0.872340 (4655 3330);
PAINT PEACH (4655 3330);
DISPLAY INVISIBLE (4655 3330);
FORCEPROP 2 LAST PATH I48
J 0
(5075 3475);
DISPLAY 1.021277 (5075 3475);
DISPLAY INVISIBLE (5075 3475);
FORCEADD OFFPAGE..2
(1375 2200);
FORCEPROP 2 LAST $XR0 14 
J 0
(1564 2200);
DISPLAY 0.638298 (1564 2200);
PAINT MONO (1564 2200);
FORCEPROP 2 LAST $XR1 10 
J 0
(1654 2200);
DISPLAY 0.638298 (1654 2200);
PAINT MONO (1654 2200);
FORCEPROP 2 LAST CDS_LIB standard
J 0
(1375 2200);
DISPLAY INVISIBLE (1375 2200);
FORCEPROP 1 LAST OFFPAGE TRUE
J 0
(1700 2075);
DISPLAY 0.872340 (1700 2075);
PAINT GREEN (1700 2075);
DISPLAY INVISIBLE (1700 2075);
FORCEPROP 1 LAST COMMENT_BODY TRUE
J 0
(1330 2105);
DISPLAY 0.872340 (1330 2105);
PAINT PEACH (1330 2105);
DISPLAY INVISIBLE (1330 2105);
FORCEPROP 2 LAST PATH I87
J 0
(1825 2250);
DISPLAY 1.021277 (1825 2250);
DISPLAY INVISIBLE (1825 2250);
FORCEADD OFFPAGE..2
(1375 2100);
FORCEPROP 2 LAST $XR0 10 
J 0
(1564 2100);
DISPLAY 0.638298 (1564 2100);
PAINT MONO (1564 2100);
FORCEPROP 2 LAST $XR1 14 
J 0
(1654 2100);
DISPLAY 0.638298 (1654 2100);
PAINT MONO (1654 2100);
FORCEPROP 2 LAST CDS_LIB standard
J 0
(1375 2100);
DISPLAY INVISIBLE (1375 2100);
FORCEPROP 1 LAST OFFPAGE TRUE
J 0
(1700 1975);
DISPLAY 0.872340 (1700 1975);
PAINT GREEN (1700 1975);
DISPLAY INVISIBLE (1700 1975);
FORCEPROP 1 LAST COMMENT_BODY TRUE
J 0
(1330 2005);
DISPLAY 0.872340 (1330 2005);
PAINT PEACH (1330 2005);
DISPLAY INVISIBLE (1330 2005);
FORCEPROP 2 LAST PATH I88
J 0
(1775 2150);
DISPLAY 1.021277 (1775 2150);
DISPLAY INVISIBLE (1775 2150);
FORCEADD UNIVERSAL_POWER..1
(-725 2300);
FORCEPROP 3 LASTPIN (-725 2250) SIG_NAME P1V2_P1V0_I3C_VDDL1\g
J 0
(-715 2260);
DISPLAY 0.659574 (-715 2260);
PAINT MONO (-715 2260);
DISPLAY INVISIBLE (-715 2260);
FORCEPROP 1 LAST HDL_POWER P1V2_P1V0_I3C_VDDL1
J 1
(-725 2350);
DISPLAY 0.702128 (-725 2350);
PAINT GREEN (-725 2350);
FORCEPROP 2 LAST CDS_LIB logical_power
J 0
(-725 2300);
DISPLAY INVISIBLE (-725 2300);
FORCEPROP 1 LAST PATH I9
J 0
(-675 2325);
DISPLAY 0.872340 (-675 2325);
PAINT AQUA (-675 2325);
DISPLAY INVISIBLE (-675 2325);
FORCEADD QUANTA_TITLE_BLOCK_C..1
(5275 -1500);
FORCEPROP 0 LAST CDS_CON_LAST_MODIFIED Fri Aug 25 17:25:37 2023
J 0
(3390 -1485);
DISPLAY INVISIBLE (3390 -1485);
FORCEPROP 2 LAST Q_DEPT 
J 1
(1512 -1451);
DISPLAY 1.957447 (1512 -1451);
PAINT GREEN (1512 -1451);
FORCEPROP 1 LAST CUSTOM_TXT_CDS <CON_LAST_MODIFIED>
J 0
(3390 -1485);
DISPLAY 0.978723 (3390 -1485);
FORCEPROP 2 LAST CUSTOM_TXT_CDS <XR_PAGE_TITLE>
J 0
(-2615 3750);
DISPLAY 0.638298 (-2615 3750);
PAINT PINK (-2615 3750);
DISPLAY INVISIBLE (-2615 3750);
FORCEPROP 1 LAST CUSTOM_TXT_CDS <NAME_2>
J 0
(2100 -1450);
FORCEPROP 1 LAST CUSTOM_TXT_CDS <NAME_1>
J 0
(2100 -1325);
FORCEPROP 1 LAST CUSTOM_TXT_CDS <Q_NUMBER>
J 0
(3872 -1397);
DISPLAY 1.212766 (3872 -1397);
FORCEPROP 1 LAST CUSTOM_TXT_CDS <Q_PROJ>
J 0
(2893 -1398);
DISPLAY 1.212766 (2893 -1398);
FORCEPROP 1 LAST CUSTOM_TXT_CDS <Q_REV>
J 0
(5091 -1397);
DISPLAY 1.212766 (5091 -1397);
FORCEPROP 1 LAST CUSTOM_TXT_CDS <CON_PAGE_NUM> OF <CON_TOTAL_PAGES>
J 0
(4829 -1482);
DISPLAY 0.978723 (4829 -1482);
FORCEPROP 1 LAST Q_TITLE BMC 3
J 0
(-4091 -1474);
DISPLAY 2.446809 (-4091 -1474);
PAINT GREEN (-4091 -1474);
FORCEPROP 2 LAST CDS_XR_PAGE_TITLE CR-14 : @SCM_LIB.SCM(SCH_1):PAGE14
J 0
(-2615 3750);
DISPLAY 0.638298 (-2615 3750);
PAINT PINK (-2615 3750);
DISPLAY INVISIBLE (-2615 3750);
FORCEPROP 1 LAST CDS_LMAN_SYM_OUTLINE -9475,6775,100,-125
J 0
(5275 -1500);
DISPLAY 0.468085 (5275 -1500);
PAINT GREEN (5275 -1500);
DISPLAY INVISIBLE (5275 -1500);
FORCEPROP 2 LAST CDS_LIB pure_quanta
J 0
(5275 -1500);
DISPLAY INVISIBLE (5275 -1500);
FORCEPROP 2 LAST PAGE_BORDER TRUE
J 0
(-2615 3750);
DISPLAY 0.638298 (-2615 3750);
PAINT PINK (-2615 3750);
DISPLAY INVISIBLE (-2615 3750);
FORCEPROP 1 LAST COMMENT_BODY TRUE
J 0
(5287 -1513);
DISPLAY 0.978723 (5287 -1513);
PAINT PEACH (5287 -1513);
DISPLAY INVISIBLE (5287 -1513);
FORCEADD DNS..1
(4400 4325);
PAINT RED (4400 4325);
FORCEPROP 2 LAST CDS_LIB mstr_misc
J 0
(4400 4325);
DISPLAY INVISIBLE (4400 4325);
FORCEPROP 1 LAST COMMENT_BODY TRUE
R 1
J 0
(4475 4100);
DISPLAY 0.872340 (4475 4100);
PAINT PEACH (4475 4100);
DISPLAY INVISIBLE (4475 4100);
FORCEADD DNS..1
(4625 3775);
PAINT RED (4625 3775);
FORCEPROP 2 LAST CDS_LIB mstr_misc
J 0
(4625 3775);
DISPLAY INVISIBLE (4625 3775);
FORCEPROP 1 LAST COMMENT_BODY TRUE
R 1
J 0
(4700 3550);
DISPLAY 0.872340 (4700 3550);
PAINT PEACH (4700 3550);
DISPLAY INVISIBLE (4700 3550);
FORCEADD DNS..1
(4875 3750);
PAINT RED (4875 3750);
FORCEPROP 1 LAST COMMENT_BODY TRUE
R 1
J 0
(4950 3525);
DISPLAY 0.872340 (4950 3525);
PAINT PEACH (4950 3525);
DISPLAY INVISIBLE (4950 3525);
FORCEPROP 2 LAST CDS_LIB mstr_misc
J 0
(4875 3750);
DISPLAY INVISIBLE (4875 3750);
FORCEADD DESIGN_NOTE..1
(2925 2850);
FORCEPROP 1 LAST COMMENT_BODY TRUE
J 0
(2950 2950);
DISPLAY 0.978723 (2950 2950);
PAINT PEACH (2950 2950);
DISPLAY INVISIBLE (2950 2950);
FORCEPROP 2 LAST CDS_LIB logical_power
J 0
(2925 2850);
DISPLAY INVISIBLE (2925 2850);
FORCEADD DNS..1
(-2875 1575);
PAINT RED (-2875 1575);
FORCEPROP 1 LAST COMMENT_BODY TRUE
R 1
J 0
(-2800 1350);
DISPLAY 0.872340 (-2800 1350);
PAINT PEACH (-2800 1350);
DISPLAY INVISIBLE (-2800 1350);
FORCEPROP 2 LAST CDS_LIB mstr_misc
J 0
(-2875 1575);
DISPLAY INVISIBLE (-2875 1575);
FORCEADD DNS..1
(-3125 1575);
PAINT RED (-3125 1575);
FORCEPROP 2 LAST CDS_LIB mstr_misc
J 0
(-3125 1575);
DISPLAY INVISIBLE (-3125 1575);
FORCEPROP 1 LAST COMMENT_BODY TRUE
R 1
J 0
(-3050 1350);
DISPLAY 0.872340 (-3050 1350);
PAINT PEACH (-3050 1350);
DISPLAY INVISIBLE (-3050 1350);
FORCEADD DNS..1
(-3125 975);
PAINT RED (-3125 975);
FORCEPROP 2 LAST CDS_LIB mstr_misc
J 0
(-3125 975);
DISPLAY INVISIBLE (-3125 975);
FORCEPROP 1 LAST COMMENT_BODY TRUE
R 1
J 0
(-3050 750);
DISPLAY 0.872340 (-3050 750);
PAINT PEACH (-3050 750);
DISPLAY INVISIBLE (-3050 750);
FORCEADD DNS..1
(-2850 975);
PAINT RED (-2850 975);
FORCEPROP 2 LAST CDS_LIB mstr_misc
J 0
(-2850 975);
DISPLAY INVISIBLE (-2850 975);
FORCEPROP 1 LAST COMMENT_BODY TRUE
R 1
J 0
(-2775 750);
DISPLAY 0.872340 (-2775 750);
PAINT PEACH (-2775 750);
DISPLAY INVISIBLE (-2775 750);
WIRE 16 -1 (-2875 1900)(-2875 2000);
WIRE 16 -1 (-2875 1900)(-2875 1700);
WIRE 16 -1 (-3100 1900)(-2875 1900);
WIRE 16 -1 (-725 2200)(-725 2250);
WIRE 16 -1 (-375 2200)(-725 2200);
WIRE 16 -1 (-725 2100)(-725 2200);
WIRE 16 -1 (3100 5000)(3100 4975);
WIRE 16 -1 (4850 4550)(4850 4575);
WIRE 16 -1 (4850 4550)(4850 4450);
WIRE 16 -1 (4625 4550)(4850 4550);
WIRE 16 -1 (-2975 775)(-2975 700);
WIRE 16 -1 (-3100 775)(-2975 775);
WIRE 16 -1 (-2975 775)(-2875 775);
WIRE 16 -1 (4850 3600)(4850 3575);
WIRE 16 -1 (4850 3600)(4850 3700);
WIRE 16 -1 (4625 3600)(4850 3600);
WIRE 16 3135 (-3700 575)(-3700 2225);
WIRE 16 3135 (-3700 575)(-1350 575);
WIRE 16 3135 (-1350 2225)(-3700 2225);
WIRE 16 3135 (-1350 2225)(-1350 575);
WIRE 16 -1 (1325 1475)(-175 1475);
FORCEPROP 2 LAST SIG_NAME I3C4_SPD_SDA
J 0
(190 1485);
DISPLAY 0.808511 (190 1485);
WIRE 16 -1 (1325 1575)(-175 1575);
FORCEPROP 2 LAST SIG_NAME I3C4_SPD_SCL
J 0
(190 1585);
DISPLAY 0.808511 (190 1585);
WIRE 16 -1 (1325 1700)(-175 1700);
FORCEPROP 2 LAST SIG_NAME I3C3_SPD_SDA
J 0
(190 1710);
DISPLAY 0.808511 (190 1710);
WIRE 16 -1 (-175 1900)(1325 1900);
FORCEPROP 2 LAST SIG_NAME I3C2_SPD_SDA
J 0
(190 1910);
DISPLAY 0.808511 (190 1910);
WIRE 16 -1 (-175 2000)(1325 2000);
FORCEPROP 2 LAST SIG_NAME I3C2_SPD_SCL
J 0
(190 2010);
DISPLAY 0.808511 (190 2010);
WIRE 16 -1 (-175 2200)(1325 2200);
FORCEPROP 2 LAST SIG_NAME I3C1_SPD_SCL
J 0
(190 2210);
DISPLAY 0.808511 (190 2210);
WIRE 16 -1 (-2050 3375)(-650 3375);
FORCEPROP 2 LAST SIG_NAME I3C1_SDA_R
J 0
(-1610 3385);
DISPLAY 0.808511 (-1610 3385);
WIRE 16 3135 (-2375 3175)(-2375 3550);
WIRE 16 3135 (-2375 3175)(-1950 3175);
WIRE 16 3135 (-1950 3550)(-2375 3550);
WIRE 16 3135 (-1950 3550)(-1950 3175);
WIRE 16 -1 (4625 4075)(4625 3900);
WIRE 16 -1 (4625 4250)(4625 4075);
WIRE 16 -1 (1700 4075)(4625 4075);
FORCEPROP 2 LAST SIG_NAME FM_BOARD_BMC_REV_ID1
J 0
(3415 4085);
DISPLAY 0.851064 (3415 4085);
WIRE 16 -1 (4850 3900)(4850 4125);
WIRE 16 -1 (4850 4250)(4850 4125);
WIRE 16 -1 (1700 4125)(4850 4125);
FORCEPROP 2 LAST SIG_NAME FM_BOARD_BMC_REV_ID0
J 0
(3415 4135);
DISPLAY 0.851064 (3415 4135);
WIRE 16 -1 (3200 3225)(4650 3225);
FORCEPROP 2 LAST SIG_NAME I3C4_SPD_SDA
J 0
(3490 3235);
DISPLAY 0.808511 (3490 3235);
WIRE 16 -1 (4650 3275)(3200 3275);
FORCEPROP 2 LAST SIG_NAME I3C4_SPD_SCL
J 0
(3490 3285);
DISPLAY 0.808511 (3490 3285);
WIRE 16 -1 (4650 3375)(3200 3375);
FORCEPROP 2 LAST SIG_NAME I3C3_SPD_SDA
J 0
(3490 3385);
DISPLAY 0.808511 (3490 3385);
WIRE 16 -1 (4650 3425)(3200 3425);
FORCEPROP 2 LAST SIG_NAME I3C3_SPD_SCL
J 0
(3490 3435);
DISPLAY 0.808511 (3490 3435);
WIRE 16 3135 (4225 3475)(5075 3475);
WIRE 16 3135 (4225 3475)(4225 4750);
WIRE 16 3135 (5075 4750)(5075 3475);
WIRE 16 3135 (5075 4750)(4225 4750);
WIRE 16 -1 (4400 4025)(4400 3900);
WIRE 16 -1 (4400 4250)(4400 4025);
WIRE 16 -1 (1700 4025)(4400 4025);
FORCEPROP 2 LAST SIG_NAME FM_BOARD_BMC_REV_ID2
J 0
(3415 4035);
DISPLAY 0.851064 (3415 4035);
WIRE 16 -1 (4400 4550)(4400 4450);
WIRE 16 -1 (4400 4550)(4625 4550);
WIRE 16 -1 (4625 4550)(4625 4450);
WIRE 16 3135 (2450 2350)(4425 2350);
WIRE 16 3135 (4425 2350)(4425 2750);
WIRE 16 3135 (2450 2350)(2450 2750);
WIRE 16 3135 (2450 2750)(4425 2750);
WIRE 16 3135 (3975 2700)(3975 2375);
WIRE 16 3135 (2475 2650)(4400 2650);
WIRE 16 3135 (2475 2550)(4400 2550);
WIRE 16 3135 (2475 2450)(4400 2450);
WIRE 16 3135 (3425 2725)(3425 2375);
WIRE 16 3135 (2800 2725)(2800 2375);
WIRE 16 3135 (3150 2725)(3150 2375);
WIRE 16 -1 (-2875 775)(-2875 875);
WIRE 16 -1 (-3100 875)(-3100 775);
WIRE 16 -1 (4400 3700)(4400 3600);
WIRE 16 -1 (4625 3700)(4625 3600);
WIRE 16 -1 (4400 3600)(4625 3600);
WIRE 16 -1 (-3100 1900)(-3100 1700);
WIRE 16 -1 (-375 2100)(-725 2100);
WIRE 16 -1 (-375 2000)(-725 2000);
WIRE 16 -1 (-725 2000)(-725 2100);
WIRE 16 -1 (-725 2000)(-725 1900);
WIRE 16 -1 (-375 1900)(-725 1900);
WIRE 16 -1 (-725 1800)(-725 1900);
WIRE 16 -1 (-375 1800)(-725 1800);
WIRE 16 -1 (-725 1800)(-725 1700);
WIRE 16 -1 (-375 1700)(-725 1700);
WIRE 16 -1 (-725 1700)(-725 1575);
WIRE 16 -1 (-375 1575)(-725 1575);
WIRE 16 -1 (-725 1475)(-725 1575);
WIRE 16 -1 (-375 1475)(-725 1475);
WIRE 16 3135 (3700 2725)(3700 2375);
WIRE 16 -1 (-2050 3425)(-650 3425);
FORCEPROP 2 LAST SIG_NAME I3C1_SCL_R
J 0
(-1610 3435);
DISPLAY 0.808511 (-1610 3435);
WIRE 16 -1 (-3575 3375)(-2250 3375);
FORCEPROP 2 LAST SIG_NAME I3C1_SPD_SDA
J 0
(-3585 3385);
DISPLAY 0.808511 (-3585 3385);
WIRE 16 -1 (3000 3425)(1700 3425);
FORCEPROP 2 LAST SIG_NAME I3C3_SCL_R
J 0
(2265 3435);
DISPLAY 0.808511 (2265 3435);
WIRE 16 -1 (3000 3275)(1700 3275);
FORCEPROP 2 LAST SIG_NAME I3C4_SCL_R
J 0
(2265 3285);
DISPLAY 0.808511 (2265 3285);
WIRE 16 -1 (3000 3225)(1700 3225);
FORCEPROP 2 LAST SIG_NAME I3C4_SDA_R
J 0
(2265 3235);
DISPLAY 0.808511 (2265 3235);
WIRE 16 -1 (3000 3375)(1700 3375);
FORCEPROP 2 LAST SIG_NAME I3C3_SDA_R
J 0
(2265 3385);
DISPLAY 0.808511 (2265 3385);
WIRE 16 -1 (3100 4675)(2900 4675);
WIRE 16 -1 (3100 4775)(3100 4675);
WIRE 16 -1 (3725 4675)(3100 4675);
FORCEPROP 2 LAST SIG_NAME AC_PWR_BMC_BTN_N
J 2
(3740 4685);
DISPLAY 0.808511 (3740 4685);
WIRE 16 -1 (-3575 3275)(-2250 3275);
FORCEPROP 2 LAST SIG_NAME I3C2_SPD_SCL
J 0
(-3585 3285);
DISPLAY 0.808511 (-3585 3285);
WIRE 16 -1 (-175 2100)(1325 2100);
FORCEPROP 2 LAST SIG_NAME I3C1_SPD_SDA
J 0
(190 2110);
DISPLAY 0.808511 (190 2110);
WIRE 16 3135 (2850 3150)(2850 3525);
WIRE 16 3135 (2850 3150)(3275 3150);
WIRE 16 3135 (3275 3525)(2850 3525);
WIRE 16 3135 (3275 3525)(3275 3150);
WIRE 16 -1 (-2050 3275)(-650 3275);
FORCEPROP 2 LAST SIG_NAME I3C2_SCL_R
J 0
(-1610 3285);
DISPLAY 0.808511 (-1610 3285);
WIRE 16 -1 (-3575 3425)(-2250 3425);
FORCEPROP 2 LAST SIG_NAME I3C1_SPD_SCL
J 0
(-3585 3435);
DISPLAY 0.808511 (-3585 3435);
WIRE 16 -1 (-2050 3225)(-650 3225);
FORCEPROP 2 LAST SIG_NAME I3C2_SDA_R
J 0
(-1610 3235);
DISPLAY 0.808511 (-1610 3235);
WIRE 16 3135 (1800 4575)(1800 5150);
WIRE 16 3135 (1800 4575)(4000 4575);
WIRE 16 3135 (4000 5150)(1800 5150);
WIRE 16 3135 (4000 5150)(4000 4575);
WIRE 16 -1 (-3575 3225)(-2250 3225);
FORCEPROP 2 LAST SIG_NAME I3C2_SPD_SDA
J 0
(-3585 3235);
DISPLAY 0.808511 (-3585 3235);
WIRE 16 -1 (1700 4675)(2700 4675);
FORCEPROP 2 LAST SIG_NAME AC_PWR_BMC_BTN_R_N
J 0
(1815 4685);
DISPLAY 0.851064 (1815 4685);
WIRE 16 -1 (1325 1800)(-175 1800);
FORCEPROP 2 LAST SIG_NAME I3C3_SPD_SCL
J 0
(190 1810);
DISPLAY 0.808511 (190 1810);
WIRE 16 -1 (-3100 1350)(-3100 1075);
WIRE 16 -1 (-3100 1500)(-3100 1350);
WIRE 16 -1 (-3100 1350)(-2075 1350);
FORCEPROP 2 LAST SIG_NAME BMC_EMMC_WP_N
J 0
(-2585 1360);
DISPLAY 0.808511 (-2585 1360);
WIRE 16 -1 (-2875 1400)(-2875 1075);
WIRE 16 -1 (-2875 1500)(-2875 1400);
WIRE 16 -1 (-2875 1400)(-2075 1400);
FORCEPROP 2 LAST SIG_NAME BMC_EMMC_CD_N
J 0
(-2585 1410);
DISPLAY 0.808511 (-2585 1410);
DOT 1 (4850 4550);
DOT 1 (4400 4025);
DOT 1 (4850 4125);
DOT 1 (-725 2200);
DOT 1 (-725 1575);
DOT 1 (4625 4075);
DOT 1 (4625 3600);
DOT 1 (3100 4675);
DOT 1 (-725 1700);
DOT 1 (-725 1800);
DOT 1 (4625 4550);
DOT 1 (-2975 775);
DOT 1 (-3100 1350);
DOT 1 (-725 2000);
DOT 1 (-2875 1400);
DOT 1 (4850 3600);
DOT 1 (-725 1900);
DOT 1 (-2875 1900);
DOT 1 (-725 2100);
FORCENOTE
CHANGE CLK TO 110OHM, DTA TO 33OHM_20221221
(-3100 3600) 0;
DISPLAY LEFT (-3100 3600);
DISPLAY 1.021277 (-3100 3600);
PAINT WHITE (-3100 3600);
FORCENOTE
CHANGE CLK TO 110OHM, DTA TO 33OHM_20221221
(2125 3575) 0;
DISPLAY LEFT (2125 3575);
DISPLAY 1.021277 (2125 3575);
PAINT WHITE (2125 3575);
FORCENOTE
EVT
(3775 2675) 0;
DISPLAY LEFT (3775 2675);
DISPLAY 1.021277 (3775 2675);
FORCENOTE
0
(3525 2575) 0;
DISPLAY LEFT (3525 2575);
DISPLAY 1.021277 (3525 2575);
FORCENOTE
1
(3525 2475) 0;
DISPLAY LEFT (3525 2475);
DISPLAY 1.021277 (3525 2475);
FORCENOTE
MP
(2575 2675) 0;
DISPLAY LEFT (2575 2675);
DISPLAY 1.021277 (2575 2675);
FORCENOTE
PVT
(3225 2675) 0;
DISPLAY LEFT (3225 2675);
DISPLAY 1.021277 (3225 2675);
FORCENOTE
PILOT
(2850 2675) 0;
DISPLAY LEFT (2850 2675);
DISPLAY 1.021277 (2850 2675);
FORCENOTE
0
(2900 2475) 0;
DISPLAY LEFT (2900 2475);
DISPLAY 1.021277 (2900 2475);
FORCENOTE
1
(2600 2475) 0;
DISPLAY LEFT (2600 2475);
DISPLAY 1.021277 (2600 2475);
FORCENOTE
1
(3250 2475) 0;
DISPLAY LEFT (3250 2475);
DISPLAY 1.021277 (3250 2475);
FORCENOTE
0
(3250 2575) 0;
DISPLAY LEFT (3250 2575);
DISPLAY 1.021277 (3250 2575);
FORCENOTE
1
(3250 2375) 0;
DISPLAY LEFT (3250 2375);
DISPLAY 1.021277 (3250 2375);
FORCENOTE
1
(2600 2575) 0;
DISPLAY LEFT (2600 2575);
DISPLAY 1.021277 (2600 2575);
FORCENOTE
0
(2600 2375) 0;
DISPLAY LEFT (2600 2375);
DISPLAY 1.021277 (2600 2375);
FORCENOTE
1
(2900 2375) 0;
DISPLAY LEFT (2900 2375);
DISPLAY 1.021277 (2900 2375);
FORCENOTE
1
(2900 2575) 0;
DISPLAY LEFT (2900 2575);
DISPLAY 1.021277 (2900 2575);
FORCENOTE
ID2
(4125 2375) 0;
DISPLAY LEFT (4125 2375);
DISPLAY 1.021277 (4125 2375);
FORCENOTE
ADD BOARD ID
(4200 4800) 0;
DISPLAY LEFT (4200 4800);
DISPLAY 1.021277 (4200 4800);
PAINT WHITE (4200 4800);
FORCENOTE
FUNCTION
(4025 2675) 0;
DISPLAY LEFT (4025 2675);
DISPLAY 1.021277 (4025 2675);
FORCENOTE
ID1
(4125 2475) 0;
DISPLAY LEFT (4125 2475);
DISPLAY 1.021277 (4125 2475);
FORCENOTE
ID0
(4125 2575) 0;
DISPLAY LEFT (4125 2575);
DISPLAY 1.021277 (4125 2575);
FORCENOTE
DVT
(3500 2675) 0;
DISPLAY LEFT (3500 2675);
DISPLAY 1.021277 (3500 2675);
FORCENOTE
0
(3525 2375) 0;
DISPLAY LEFT (3525 2375);
DISPLAY 1.021277 (3525 2375);
FORCENOTE
0
(3825 2375) 0;
DISPLAY LEFT (3825 2375);
DISPLAY 1.021277 (3825 2375);
FORCENOTE
0
(3825 2475) 0;
DISPLAY LEFT (3825 2475);
DISPLAY 1.021277 (3825 2475);
FORCENOTE
1
(3825 2575) 0;
DISPLAY LEFT (3825 2575);
DISPLAY 1.021277 (3825 2575);
FORCENOTE
AC POWER BTN
(1200 5075) 0;
DISPLAY LEFT (1200 5075);
DISPLAY 1.021277 (1200 5075);
PAINT WHITE (1200 5075);
FORCENOTE
IF IMPLEMENTING EMMC, PLEASE POP R686 AND R685
(-3650 2375) 0;
DISPLAY LEFT (-3650 2375);
DISPLAY 1.021277 (-3650 2375);
PAINT WHITE (-3650 2375);
QUIT
